G04 ================== begin FILE IDENTIFICATION RECORD ==================*
G04 Layout Name:  D:/<user>/Wistron_project/16315-1/gbr/16315-1.brd*
G04 Film Name:    SE_REF_L5*
G04 File Format:  Gerber RS274X*
G04 File Origin:  Cadence Allegro 16.5-S056*
G04 Origin Date:  Fri Jun 09 15:32:46 2017*
G04 *
G04 Layer:  BOARD GEOMETRY/SE_REF_L5_TBL*
G04 Layer:  BOARD GEOMETRY/SE_REF_L5_L5*
G04 Layer:  BOARD GEOMETRY/PANEL_OUTLINE*
G04 *
G04 Offset:    (0.00 0.00)*
G04 Mirror:    No*
G04 Mode:      Positive*
G04 Rotation:  0*
G04 FullContactRelief:  No*
G04 UndefLineWidth:     6.00*
G04 ================== end FILE IDENTIFICATION RECORD ====================*
%FSLAX35Y35*MOIN*%
%IR0*IPPOS*OFA0.00000B0.00000*MIA0B0*SFA1.00000B1.00000*%
%ADD10C,.02*%
%ADD11C,.006*%
%ADD12C,.00475*%
G75*
%LPD*%
G75*
G54D10*
G01X1985143Y1554618D02*
X2720143D01*
G01X1985143Y1623918D02*
Y1554618D01*
G01Y1589268D02*
X2720143D01*
G01X1985143Y1623918D02*
X2720143D01*
G01X2160143D02*
Y1554618D01*
G01X2405143Y1623918D02*
Y1554618D01*
G01X2510143Y1623918D02*
Y1554618D01*
G01X2720143Y1623918D02*
Y1554618D01*
G54D11*
G01X6250Y-185556D02*
Y-203056D01*
G01X1228Y-185556D02*
X11272D01*
G01X20038Y-203056D02*
Y-185556D01*
G01Y-194014D02*
X21130Y-192556D01*
X22222Y-191681D01*
X23968Y-191390D01*
X25278Y-191681D01*
X26807Y-192848D01*
X27462Y-194598D01*
Y-203056D01*
G01X41250Y-191390D02*
Y-203056D01*
G01Y-186723D02*
X40813Y-186431D01*
Y-185848D01*
X41250Y-185556D01*
X41687Y-185848D01*
Y-186431D01*
X41250Y-186723D01*
G01X55475Y-201015D02*
X56567Y-202181D01*
X58095Y-203056D01*
X59405D01*
X60715Y-202473D01*
X61588Y-201598D01*
X62025Y-200432D01*
X61807Y-198681D01*
X60933Y-197806D01*
X57003Y-196056D01*
X56130Y-194014D01*
X56567Y-192556D01*
X57440Y-191681D01*
X58750Y-191390D01*
X60060Y-191681D01*
X61370Y-192556D01*
G01X90693Y-207431D02*
X92222Y-208598D01*
X93968Y-208889D01*
X95496Y-208598D01*
X96807Y-207140D01*
X97680Y-205098D01*
Y-191390D01*
G01Y-193723D02*
X96807Y-192556D01*
X95496Y-191681D01*
X93968Y-191390D01*
X92222Y-191973D01*
X91130Y-193139D01*
X90256Y-195181D01*
X89820Y-197223D01*
X90038Y-198973D01*
X90912Y-201015D01*
X92222Y-202473D01*
X93968Y-203056D01*
X95278Y-202764D01*
X96807Y-201598D01*
X97680Y-200432D01*
G01X107975Y-195181D02*
X114962D01*
X114307Y-193139D01*
X113215Y-191973D01*
X111687Y-191390D01*
X110158Y-191681D01*
X108848Y-192556D01*
X107975Y-194598D01*
X107538Y-196348D01*
Y-198098D01*
X107975Y-199848D01*
X109067Y-201598D01*
X110377Y-202764D01*
X111905Y-203056D01*
X113433Y-202473D01*
X114962Y-200723D01*
G01X125693Y-203056D02*
Y-191390D01*
G01Y-193723D02*
X126785Y-192556D01*
X127877Y-191681D01*
X129405Y-191390D01*
X130496Y-191681D01*
X131807Y-192556D01*
G01X142320Y-203056D02*
Y-185556D01*
G01Y-194306D02*
X143412Y-192556D01*
X144722Y-191681D01*
X146032Y-191390D01*
X147996Y-191973D01*
X149307Y-193139D01*
X150180Y-195181D01*
Y-197514D01*
X149743Y-199848D01*
X148870Y-201598D01*
X147342Y-202764D01*
X146032Y-203056D01*
X144722Y-202764D01*
X143412Y-201890D01*
X142320Y-200432D01*
G01X160475Y-195181D02*
X167462D01*
X166807Y-193139D01*
X165715Y-191973D01*
X164187Y-191390D01*
X162658Y-191681D01*
X161348Y-192556D01*
X160475Y-194598D01*
X160038Y-196348D01*
Y-198098D01*
X160475Y-199848D01*
X161567Y-201598D01*
X162877Y-202764D01*
X164405Y-203056D01*
X165933Y-202473D01*
X167462Y-200723D01*
G01X178193Y-203056D02*
Y-191390D01*
G01Y-193723D02*
X179285Y-192556D01*
X180377Y-191681D01*
X181905Y-191390D01*
X182996Y-191681D01*
X184307Y-192556D01*
G01X216250Y-191390D02*
Y-203056D01*
G01Y-186723D02*
X215813Y-186431D01*
Y-185848D01*
X216250Y-185556D01*
X216687Y-185848D01*
Y-186431D01*
X216250Y-186723D01*
G01X230475Y-201015D02*
X231567Y-202181D01*
X233095Y-203056D01*
X234405D01*
X235715Y-202473D01*
X236588Y-201598D01*
X237025Y-200432D01*
X236807Y-198681D01*
X235933Y-197806D01*
X232003Y-196056D01*
X231130Y-194014D01*
X231567Y-192556D01*
X232440Y-191681D01*
X233750Y-191390D01*
X235060Y-191681D01*
X236370Y-192556D01*
G01X265256Y-207431D02*
X266785Y-208598D01*
X268095Y-208889D01*
X269842Y-208306D01*
X271152Y-206848D01*
X271807Y-204222D01*
Y-191390D01*
G01Y-186723D02*
X271370Y-186431D01*
Y-185848D01*
X271807Y-185556D01*
X272243Y-185848D01*
Y-186431D01*
X271807Y-186723D01*
G01X282538Y-191390D02*
Y-199556D01*
X283412Y-201598D01*
X284722Y-202764D01*
X286250Y-203056D01*
X287778Y-202764D01*
X289088Y-201598D01*
X289962Y-199556D01*
G01Y-203056D02*
Y-191390D01*
G01X300475Y-201015D02*
X301567Y-202181D01*
X303095Y-203056D01*
X304405D01*
X305715Y-202473D01*
X306588Y-201598D01*
X307025Y-200432D01*
X306807Y-198681D01*
X305933Y-197806D01*
X302003Y-196056D01*
X301130Y-194014D01*
X301567Y-192556D01*
X302440Y-191681D01*
X303750Y-191390D01*
X305060Y-191681D01*
X306370Y-192556D01*
G01X321250Y-185556D02*
Y-203056D01*
G01X318193Y-191390D02*
X324307D01*
G01X354940Y-203056D02*
Y-188181D01*
X355377Y-186723D01*
X356250Y-185848D01*
X357560Y-185556D01*
X358870Y-186139D01*
X359525Y-187598D01*
G01X356905Y-192556D02*
X352538D01*
G01X373750Y-203056D02*
X372440Y-202764D01*
X371130Y-201598D01*
X370256Y-199556D01*
X369820Y-197223D01*
X370256Y-194889D01*
X371130Y-192848D01*
X372440Y-191681D01*
X373750Y-191390D01*
X375060Y-191681D01*
X376370Y-192848D01*
X377243Y-194889D01*
X377462Y-197223D01*
X377243Y-199556D01*
X376370Y-201598D01*
X375060Y-202764D01*
X373750Y-203056D01*
G01X388193D02*
Y-191390D01*
G01Y-193723D02*
X389285Y-192556D01*
X390377Y-191681D01*
X391905Y-191390D01*
X392996Y-191681D01*
X394307Y-192556D01*
G01X421665Y-208306D02*
X422975Y-208889D01*
X424722Y-208306D01*
X425813Y-207140D01*
X426687Y-205681D01*
X427996Y-201015D01*
X430835Y-191390D01*
G01X423848D02*
X427996Y-201015D01*
G01X443750Y-203056D02*
X442440Y-202764D01*
X441130Y-201598D01*
X440256Y-199556D01*
X439820Y-197223D01*
X440256Y-194889D01*
X441130Y-192848D01*
X442440Y-191681D01*
X443750Y-191390D01*
X445060Y-191681D01*
X446370Y-192848D01*
X447243Y-194889D01*
X447462Y-197223D01*
X447243Y-199556D01*
X446370Y-201598D01*
X445060Y-202764D01*
X443750Y-203056D01*
G01X457538Y-191390D02*
Y-199556D01*
X458412Y-201598D01*
X459722Y-202764D01*
X461250Y-203056D01*
X462778Y-202764D01*
X464088Y-201598D01*
X464962Y-199556D01*
G01Y-203056D02*
Y-191390D01*
G01X475693Y-203056D02*
Y-191390D01*
G01Y-193723D02*
X476785Y-192556D01*
X477877Y-191681D01*
X479405Y-191390D01*
X480496Y-191681D01*
X481807Y-192556D01*
G01X510693Y-203056D02*
Y-191390D01*
G01Y-193723D02*
X511785Y-192556D01*
X512877Y-191681D01*
X514405Y-191390D01*
X515496Y-191681D01*
X516807Y-192556D01*
G01X527975Y-195181D02*
X534962D01*
X534307Y-193139D01*
X533215Y-191973D01*
X531687Y-191390D01*
X530158Y-191681D01*
X528848Y-192556D01*
X527975Y-194598D01*
X527538Y-196348D01*
Y-198098D01*
X527975Y-199848D01*
X529067Y-201598D01*
X530377Y-202764D01*
X531905Y-203056D01*
X533433Y-202473D01*
X534962Y-200723D01*
G01X547440Y-203056D02*
Y-188181D01*
X547877Y-186723D01*
X548750Y-185848D01*
X550060Y-185556D01*
X551370Y-186139D01*
X552025Y-187598D01*
G01X549405Y-192556D02*
X545038D01*
G01X562975Y-195181D02*
X569962D01*
X569307Y-193139D01*
X568215Y-191973D01*
X566687Y-191390D01*
X565158Y-191681D01*
X563848Y-192556D01*
X562975Y-194598D01*
X562538Y-196348D01*
Y-198098D01*
X562975Y-199848D01*
X564067Y-201598D01*
X565377Y-202764D01*
X566905Y-203056D01*
X568433Y-202473D01*
X569962Y-200723D01*
G01X580693Y-203056D02*
Y-191390D01*
G01Y-193723D02*
X581785Y-192556D01*
X582877Y-191681D01*
X584405Y-191390D01*
X585496Y-191681D01*
X586807Y-192556D01*
G01X597975Y-195181D02*
X604962D01*
X604307Y-193139D01*
X603215Y-191973D01*
X601687Y-191390D01*
X600158Y-191681D01*
X598848Y-192556D01*
X597975Y-194598D01*
X597538Y-196348D01*
Y-198098D01*
X597975Y-199848D01*
X599067Y-201598D01*
X600377Y-202764D01*
X601905Y-203056D01*
X603433Y-202473D01*
X604962Y-200723D01*
G01X615038Y-203056D02*
Y-191390D01*
G01Y-194306D02*
X615912Y-192848D01*
X617222Y-191681D01*
X618968Y-191390D01*
X620496Y-191681D01*
X621807Y-192848D01*
X622462Y-194889D01*
Y-203056D01*
G01X639743Y-192848D02*
X638215Y-191681D01*
X636905Y-191390D01*
X635158Y-191973D01*
X633848Y-193139D01*
X632975Y-195181D01*
X632756Y-197223D01*
X632975Y-199265D01*
X633848Y-201015D01*
X635158Y-202473D01*
X636905Y-203056D01*
X638433Y-202473D01*
X639743Y-201306D01*
G01X650475Y-195181D02*
X657462D01*
X656807Y-193139D01*
X655715Y-191973D01*
X654187Y-191390D01*
X652658Y-191681D01*
X651348Y-192556D01*
X650475Y-194598D01*
X650038Y-196348D01*
Y-198098D01*
X650475Y-199848D01*
X651567Y-201598D01*
X652877Y-202764D01*
X654405Y-203056D01*
X655933Y-202473D01*
X657462Y-200723D01*
G01X688750Y-185556D02*
Y-203056D01*
G01X685693Y-191390D02*
X691807D01*
G01X706250Y-203056D02*
X704940Y-202764D01*
X703630Y-201598D01*
X702756Y-199556D01*
X702320Y-197223D01*
X702756Y-194889D01*
X703630Y-192848D01*
X704940Y-191681D01*
X706250Y-191390D01*
X707560Y-191681D01*
X708870Y-192848D01*
X709743Y-194889D01*
X709962Y-197223D01*
X709743Y-199556D01*
X708870Y-201598D01*
X707560Y-202764D01*
X706250Y-203056D01*
G01X739940D02*
Y-188181D01*
X740377Y-186723D01*
X741250Y-185848D01*
X742560Y-185556D01*
X743870Y-186139D01*
X744525Y-187598D01*
G01X741905Y-192556D02*
X737538D01*
G01X758750Y-191390D02*
Y-203056D01*
G01Y-186723D02*
X758313Y-186431D01*
Y-185848D01*
X758750Y-185556D01*
X759187Y-185848D01*
Y-186431D01*
X758750Y-186723D01*
G01X772538Y-203056D02*
Y-191390D01*
G01Y-194306D02*
X773412Y-192848D01*
X774722Y-191681D01*
X776468Y-191390D01*
X777996Y-191681D01*
X779307Y-192848D01*
X779962Y-194889D01*
Y-203056D01*
G01X797680Y-185556D02*
Y-203056D01*
G01Y-200432D02*
X796807Y-201890D01*
X795496Y-202764D01*
X793968Y-203056D01*
X792222Y-202473D01*
X790912Y-201015D01*
X790038Y-199265D01*
X789820Y-197223D01*
X790038Y-195181D01*
X790912Y-193431D01*
X792222Y-191973D01*
X793968Y-191390D01*
X795496Y-191681D01*
X796588Y-192265D01*
X797680Y-193431D01*
G01X828750Y-185556D02*
Y-203056D01*
G01X825693Y-191390D02*
X831807D01*
G01X842538Y-203056D02*
Y-185556D01*
G01Y-194014D02*
X843630Y-192556D01*
X844722Y-191681D01*
X846468Y-191390D01*
X847778Y-191681D01*
X849307Y-192848D01*
X849962Y-194598D01*
Y-203056D01*
G01X860475Y-195181D02*
X867462D01*
X866807Y-193139D01*
X865715Y-191973D01*
X864187Y-191390D01*
X862658Y-191681D01*
X861348Y-192556D01*
X860475Y-194598D01*
X860038Y-196348D01*
Y-198098D01*
X860475Y-199848D01*
X861567Y-201598D01*
X862877Y-202764D01*
X864405Y-203056D01*
X865933Y-202473D01*
X867462Y-200723D01*
G01X894165D02*
X895912Y-202181D01*
X897877Y-203056D01*
X899623D01*
X901370Y-202181D01*
X902680Y-200723D01*
X903335Y-198681D01*
X902898Y-196640D01*
X901807Y-194889D01*
X899842Y-193723D01*
X897222Y-193139D01*
X895693Y-191973D01*
X895038Y-189931D01*
X895475Y-187889D01*
X896567Y-186431D01*
X898095Y-185556D01*
X899623D01*
X901152Y-186139D01*
X902462Y-187598D01*
G01X920617Y-203056D02*
X911883D01*
Y-185556D01*
X920617D01*
G01X917123Y-194014D02*
X911883D01*
G01X951250Y-191390D02*
Y-203056D01*
G01Y-186723D02*
X950813Y-186431D01*
Y-185848D01*
X951250Y-185556D01*
X951687Y-185848D01*
Y-186431D01*
X951250Y-186723D01*
G01X962200Y-203056D02*
Y-191390D01*
G01Y-194598D02*
X962855Y-193139D01*
X963947Y-191973D01*
X965475Y-191390D01*
X967003Y-191973D01*
X968095Y-193139D01*
X968750Y-194598D01*
Y-203056D01*
G01Y-194598D02*
X969405Y-193139D01*
X970496Y-191973D01*
X972025Y-191390D01*
X973553Y-191973D01*
X974645Y-193139D01*
X975300Y-194889D01*
Y-203056D01*
G01X982320Y-208889D02*
Y-191390D01*
G01Y-194014D02*
X983412Y-192556D01*
X984503Y-191681D01*
X986250Y-191390D01*
X987778Y-191681D01*
X989307Y-193139D01*
X989962Y-195181D01*
X990180Y-197223D01*
X989962Y-199265D01*
X989307Y-201306D01*
X987996Y-202473D01*
X986250Y-203056D01*
X984722Y-202764D01*
X983193Y-201890D01*
X982320Y-200723D01*
G01X1000475Y-195181D02*
X1007462D01*
X1006807Y-193139D01*
X1005715Y-191973D01*
X1004187Y-191390D01*
X1002658Y-191681D01*
X1001348Y-192556D01*
X1000475Y-194598D01*
X1000038Y-196348D01*
Y-198098D01*
X1000475Y-199848D01*
X1001567Y-201598D01*
X1002877Y-202764D01*
X1004405Y-203056D01*
X1005933Y-202473D01*
X1007462Y-200723D01*
G01X1025180Y-185556D02*
Y-203056D01*
G01Y-200432D02*
X1024307Y-201890D01*
X1022996Y-202764D01*
X1021468Y-203056D01*
X1019722Y-202473D01*
X1018412Y-201015D01*
X1017538Y-199265D01*
X1017320Y-197223D01*
X1017538Y-195181D01*
X1018412Y-193431D01*
X1019722Y-191973D01*
X1021468Y-191390D01*
X1022996Y-191681D01*
X1024088Y-192265D01*
X1025180Y-193431D01*
G01X1042680Y-203056D02*
Y-191390D01*
G01Y-193431D02*
X1041807Y-192265D01*
X1040496Y-191681D01*
X1038968Y-191390D01*
X1037440Y-191973D01*
X1036130Y-193139D01*
X1035256Y-194889D01*
X1034820Y-197223D01*
X1035256Y-199556D01*
X1036130Y-201306D01*
X1037440Y-202473D01*
X1038968Y-203056D01*
X1040496Y-202764D01*
X1041807Y-201890D01*
X1042680Y-200723D01*
G01X1052538Y-203056D02*
Y-191390D01*
G01Y-194306D02*
X1053412Y-192848D01*
X1054722Y-191681D01*
X1056468Y-191390D01*
X1057996Y-191681D01*
X1059307Y-192848D01*
X1059962Y-194889D01*
Y-203056D01*
G01X1077243Y-192848D02*
X1075715Y-191681D01*
X1074405Y-191390D01*
X1072658Y-191973D01*
X1071348Y-193139D01*
X1070475Y-195181D01*
X1070256Y-197223D01*
X1070475Y-199265D01*
X1071348Y-201015D01*
X1072658Y-202473D01*
X1074405Y-203056D01*
X1075933Y-202473D01*
X1077243Y-201306D01*
G01X1087975Y-195181D02*
X1094962D01*
X1094307Y-193139D01*
X1093215Y-191973D01*
X1091687Y-191390D01*
X1090158Y-191681D01*
X1088848Y-192556D01*
X1087975Y-194598D01*
X1087538Y-196348D01*
Y-198098D01*
X1087975Y-199848D01*
X1089067Y-201598D01*
X1090377Y-202764D01*
X1091905Y-203056D01*
X1093433Y-202473D01*
X1094962Y-200723D01*
G01X1126250Y-185556D02*
Y-203056D01*
G01X1123193Y-191390D02*
X1129307D01*
G01X1140693Y-203056D02*
Y-191390D01*
G01Y-193723D02*
X1141785Y-192556D01*
X1142877Y-191681D01*
X1144405Y-191390D01*
X1145496Y-191681D01*
X1146807Y-192556D01*
G01X1165180Y-203056D02*
Y-191390D01*
G01Y-193431D02*
X1164307Y-192265D01*
X1162996Y-191681D01*
X1161468Y-191390D01*
X1159940Y-191973D01*
X1158630Y-193139D01*
X1157756Y-194889D01*
X1157320Y-197223D01*
X1157756Y-199556D01*
X1158630Y-201306D01*
X1159940Y-202473D01*
X1161468Y-203056D01*
X1162996Y-202764D01*
X1164307Y-201890D01*
X1165180Y-200723D01*
G01X1182243Y-192848D02*
X1180715Y-191681D01*
X1179405Y-191390D01*
X1177658Y-191973D01*
X1176348Y-193139D01*
X1175475Y-195181D01*
X1175256Y-197223D01*
X1175475Y-199265D01*
X1176348Y-201015D01*
X1177658Y-202473D01*
X1179405Y-203056D01*
X1180933Y-202473D01*
X1182243Y-201306D01*
G01X1192975Y-195181D02*
X1199962D01*
X1199307Y-193139D01*
X1198215Y-191973D01*
X1196687Y-191390D01*
X1195158Y-191681D01*
X1193848Y-192556D01*
X1192975Y-194598D01*
X1192538Y-196348D01*
Y-198098D01*
X1192975Y-199848D01*
X1194067Y-201598D01*
X1195377Y-202764D01*
X1196905Y-203056D01*
X1198433Y-202473D01*
X1199962Y-200723D01*
G01X1210475Y-201015D02*
X1211567Y-202181D01*
X1213095Y-203056D01*
X1214405D01*
X1215715Y-202473D01*
X1216588Y-201598D01*
X1217025Y-200432D01*
X1216807Y-198681D01*
X1215933Y-197806D01*
X1212003Y-196056D01*
X1211130Y-194014D01*
X1211567Y-192556D01*
X1212440Y-191681D01*
X1213750Y-191390D01*
X1215060Y-191681D01*
X1216370Y-192556D01*
G01X1248750Y-191390D02*
Y-203056D01*
G01Y-186723D02*
X1248313Y-186431D01*
Y-185848D01*
X1248750Y-185556D01*
X1249187Y-185848D01*
Y-186431D01*
X1248750Y-186723D01*
G01X1262538Y-203056D02*
Y-191390D01*
G01Y-194306D02*
X1263412Y-192848D01*
X1264722Y-191681D01*
X1266468Y-191390D01*
X1267996Y-191681D01*
X1269307Y-192848D01*
X1269962Y-194889D01*
Y-203056D01*
G01X1301250D02*
Y-185556D01*
G01X1322680Y-203056D02*
Y-191390D01*
G01Y-193431D02*
X1321807Y-192265D01*
X1320496Y-191681D01*
X1318968Y-191390D01*
X1317440Y-191973D01*
X1316130Y-193139D01*
X1315256Y-194889D01*
X1314820Y-197223D01*
X1315256Y-199556D01*
X1316130Y-201306D01*
X1317440Y-202473D01*
X1318968Y-203056D01*
X1320496Y-202764D01*
X1321807Y-201890D01*
X1322680Y-200723D01*
G01X1331665Y-208306D02*
X1332975Y-208889D01*
X1334722Y-208306D01*
X1335813Y-207140D01*
X1336687Y-205681D01*
X1337996Y-201015D01*
X1340835Y-191390D01*
G01X1333848D02*
X1337996Y-201015D01*
G01X1350475Y-195181D02*
X1357462D01*
X1356807Y-193139D01*
X1355715Y-191973D01*
X1354187Y-191390D01*
X1352658Y-191681D01*
X1351348Y-192556D01*
X1350475Y-194598D01*
X1350038Y-196348D01*
Y-198098D01*
X1350475Y-199848D01*
X1351567Y-201598D01*
X1352877Y-202764D01*
X1354405Y-203056D01*
X1355933Y-202473D01*
X1357462Y-200723D01*
G01X1368193Y-203056D02*
Y-191390D01*
G01Y-193723D02*
X1369285Y-192556D01*
X1370377Y-191681D01*
X1371905Y-191390D01*
X1372996Y-191681D01*
X1374307Y-192556D01*
G01X1401883Y-185556D02*
Y-203056D01*
X1410617D01*
G01X1418947Y-200432D02*
X1420256Y-201890D01*
X1421785Y-202764D01*
X1423750Y-203056D01*
X1425715Y-202473D01*
X1427243Y-201306D01*
X1428335Y-199265D01*
X1428553Y-196931D01*
X1428117Y-194598D01*
X1427025Y-193139D01*
X1425496Y-191973D01*
X1423968Y-191681D01*
X1422440Y-191973D01*
X1420475Y-193139D01*
X1421130Y-185556D01*
X1427025D01*
G01X1441250Y-203639D02*
X1440813Y-203348D01*
Y-202764D01*
X1441250Y-202473D01*
X1441687Y-202764D01*
Y-203348D01*
X1441250Y-203639D01*
G01X2008773Y1616518D02*
X2014013D01*
G01X2011393D02*
Y1599018D01*
G01X2008773D02*
X2014013D01*
G01X2023216D02*
Y1616518D01*
X2028893Y1601935D01*
X2034570Y1616518D01*
Y1599018D01*
G01X2042026D02*
Y1616518D01*
X2047266D01*
X2049013Y1615643D01*
X2050323Y1613601D01*
X2050760Y1611268D01*
X2050323Y1608935D01*
X2049231Y1607185D01*
X2047266Y1606309D01*
X2042026D01*
G01X2062801Y1593185D02*
X2060618Y1596101D01*
X2059526Y1599018D01*
Y1610684D01*
X2060618Y1613601D01*
X2062801Y1616518D01*
G01X2081393Y1599018D02*
X2079646Y1599310D01*
X2078118Y1600476D01*
X2076808Y1602226D01*
X2075934Y1604268D01*
X2075498Y1606601D01*
Y1608935D01*
X2075934Y1611268D01*
X2076808Y1613310D01*
X2078118Y1615059D01*
X2079646Y1616226D01*
X2081393Y1616518D01*
X2083139Y1616226D01*
X2084668Y1615059D01*
X2085978Y1613310D01*
X2086852Y1611268D01*
X2087288Y1608935D01*
Y1606601D01*
X2086852Y1604268D01*
X2085978Y1602226D01*
X2084668Y1600476D01*
X2083139Y1599310D01*
X2081393Y1599018D01*
G01X2095181D02*
Y1616518D01*
G01Y1608060D02*
X2096273Y1609518D01*
X2097365Y1610393D01*
X2099111Y1610684D01*
X2100421Y1610393D01*
X2101950Y1609226D01*
X2102605Y1607476D01*
Y1599018D01*
G01X2109843D02*
Y1610684D01*
G01Y1607476D02*
X2110498Y1608935D01*
X2111590Y1610101D01*
X2113118Y1610684D01*
X2114646Y1610101D01*
X2115738Y1608935D01*
X2116393Y1607476D01*
Y1599018D01*
G01Y1607476D02*
X2117048Y1608935D01*
X2118139Y1610101D01*
X2119668Y1610684D01*
X2121196Y1610101D01*
X2122288Y1608935D01*
X2122943Y1607185D01*
Y1599018D01*
G01X2134985Y1593185D02*
X2137168Y1596101D01*
X2138260Y1599018D01*
Y1610684D01*
X2137168Y1613601D01*
X2134985Y1616518D01*
G01X1987108Y1636001D02*
X1988855Y1634543D01*
X1990820Y1633668D01*
X1992566D01*
X1994313Y1634543D01*
X1995623Y1636001D01*
X1996278Y1638043D01*
X1995841Y1640084D01*
X1994750Y1641835D01*
X1992785Y1643001D01*
X1990165Y1643585D01*
X1988636Y1644751D01*
X1987981Y1646793D01*
X1988418Y1648835D01*
X1989510Y1650293D01*
X1991038Y1651168D01*
X1992566D01*
X1994095Y1650585D01*
X1995405Y1649126D01*
G01X2013560Y1633668D02*
X2004826D01*
Y1651168D01*
X2013560D01*
G01X2010066Y1642710D02*
X2004826D01*
G01X2041573Y1651168D02*
X2046813D01*
G01X2044193D02*
Y1633668D01*
G01X2041573D02*
X2046813D01*
G01X2056016D02*
Y1651168D01*
X2061693Y1636585D01*
X2067370Y1651168D01*
Y1633668D01*
G01X2074826D02*
Y1651168D01*
X2080066D01*
X2081813Y1650293D01*
X2083123Y1648251D01*
X2083560Y1645918D01*
X2083123Y1643585D01*
X2082031Y1641835D01*
X2080066Y1640959D01*
X2074826D01*
G01X2101060Y1633668D02*
X2092326D01*
Y1651168D01*
X2101060D01*
G01X2097566Y1642710D02*
X2092326D01*
G01X2109390Y1633668D02*
Y1651168D01*
X2113756D01*
X2115503Y1650293D01*
X2116813Y1649126D01*
X2117905Y1647377D01*
X2118778Y1645334D01*
X2118996Y1642418D01*
X2118778Y1639501D01*
X2117905Y1637459D01*
X2116813Y1635709D01*
X2115503Y1634543D01*
X2113756Y1633668D01*
X2109390D01*
G01X2126234D02*
X2131693Y1651168D01*
X2137152Y1633668D01*
G01X2135186Y1639793D02*
X2128199D01*
G01X2144171Y1633668D02*
Y1651168D01*
X2154215Y1633668D01*
Y1651168D01*
G01X2171496Y1649709D02*
X2170186Y1650585D01*
X2168658Y1651168D01*
X2166911D01*
X2164946Y1650293D01*
X2163418Y1648835D01*
X2162326Y1647084D01*
X2161453Y1644168D01*
X2161234Y1641543D01*
X2161671Y1638918D01*
X2162326Y1637168D01*
X2163636Y1635418D01*
X2165165Y1634251D01*
X2166693Y1633668D01*
X2168221D01*
X2169750Y1634251D01*
X2171060Y1635126D01*
X2172152Y1636292D01*
G01X2188560Y1633668D02*
X2179826D01*
Y1651168D01*
X2188560D01*
G01X2185066Y1642710D02*
X2179826D01*
G01X2219193Y1651168D02*
Y1633668D01*
G01X2214171Y1651168D02*
X2224215D01*
G01X2231234Y1633668D02*
X2236693Y1651168D01*
X2242152Y1633668D01*
G01X2240186Y1639793D02*
X2233199D01*
G01X2255939Y1643001D02*
X2256813Y1643876D01*
X2257468Y1645334D01*
X2257905Y1647377D01*
X2257468Y1649126D01*
X2256595Y1650293D01*
X2255066Y1651168D01*
X2249171D01*
Y1633668D01*
X2256376D01*
X2257905Y1634834D01*
X2258778Y1636585D01*
X2259215Y1638626D01*
X2258778Y1640668D01*
X2257468Y1642418D01*
X2255939Y1643001D01*
X2249171D01*
G01X2267326Y1651168D02*
Y1633668D01*
X2276060D01*
G01X2293560D02*
X2284826D01*
Y1651168D01*
X2293560D01*
G01X2290066Y1642710D02*
X2284826D01*
G01X2306693Y1633085D02*
X2306256Y1633376D01*
Y1633960D01*
X2306693Y1634251D01*
X2307130Y1633960D01*
Y1633376D01*
X2306693Y1633085D01*
G01Y1640959D02*
X2306256Y1641251D01*
Y1641835D01*
X2306693Y1642126D01*
X2307130Y1641835D01*
Y1641251D01*
X2306693Y1640959D01*
G01X2337326Y1651168D02*
Y1633668D01*
X2346060D01*
G01X2354390Y1636292D02*
X2355699Y1634834D01*
X2357228Y1633960D01*
X2359193Y1633668D01*
X2361158Y1634251D01*
X2362686Y1635418D01*
X2363778Y1637459D01*
X2363996Y1639793D01*
X2363560Y1642126D01*
X2362468Y1643585D01*
X2360939Y1644751D01*
X2359411Y1645043D01*
X2357883Y1644751D01*
X2355918Y1643585D01*
X2356573Y1651168D01*
X2362468D01*
G01X2041590Y1566992D02*
X2042899Y1565534D01*
X2044428Y1564660D01*
X2046393Y1564368D01*
X2048358Y1564951D01*
X2049886Y1566118D01*
X2050978Y1568159D01*
X2051196Y1570493D01*
X2050760Y1572826D01*
X2049668Y1574285D01*
X2048139Y1575451D01*
X2046611Y1575743D01*
X2045083Y1575451D01*
X2043118Y1574285D01*
X2043773Y1581868D01*
X2049668D01*
G01X2063893D02*
X2062146Y1581285D01*
X2060836Y1579826D01*
X2059963Y1578077D01*
X2059308Y1575743D01*
X2059090Y1573118D01*
X2059308Y1570493D01*
X2059963Y1568159D01*
X2060836Y1566409D01*
X2062146Y1564951D01*
X2063893Y1564368D01*
X2065639Y1564951D01*
X2066950Y1566409D01*
X2067823Y1568159D01*
X2068478Y1570493D01*
X2068696Y1573118D01*
X2068478Y1575743D01*
X2067823Y1578077D01*
X2066950Y1579826D01*
X2065639Y1581285D01*
X2063893Y1581868D01*
G01X2081393Y1563785D02*
X2080956Y1564076D01*
Y1564660D01*
X2081393Y1564951D01*
X2081830Y1564660D01*
Y1564076D01*
X2081393Y1563785D01*
G01X2098893Y1581868D02*
X2097146Y1581285D01*
X2095836Y1579826D01*
X2094963Y1578077D01*
X2094308Y1575743D01*
X2094090Y1573118D01*
X2094308Y1570493D01*
X2094963Y1568159D01*
X2095836Y1566409D01*
X2097146Y1564951D01*
X2098893Y1564368D01*
X2100639Y1564951D01*
X2101950Y1566409D01*
X2102823Y1568159D01*
X2103478Y1570493D01*
X2103696Y1573118D01*
X2103478Y1575743D01*
X2102823Y1578077D01*
X2101950Y1579826D01*
X2100639Y1581285D01*
X2098893Y1581868D01*
G01X2188593Y1616518D02*
X2191649Y1599018D01*
X2195143Y1616518D01*
X2198636Y1599018D01*
X2201693Y1616518D01*
G01X2210023D02*
X2215263D01*
G01X2212643D02*
Y1599018D01*
G01X2210023D02*
X2215263D01*
G01X2225340D02*
Y1616518D01*
X2229706D01*
X2231453Y1615643D01*
X2232763Y1614476D01*
X2233855Y1612727D01*
X2234728Y1610684D01*
X2234946Y1607768D01*
X2234728Y1604851D01*
X2233855Y1602809D01*
X2232763Y1601059D01*
X2231453Y1599893D01*
X2229706Y1599018D01*
X2225340D01*
G01X2247643Y1616518D02*
Y1599018D01*
G01X2242621Y1616518D02*
X2252665D01*
G01X2260558Y1599018D02*
Y1616518D01*
G01X2269728D02*
Y1599018D01*
G01Y1607768D02*
X2260558D01*
G01X2281551Y1593185D02*
X2279368Y1596101D01*
X2278276Y1599018D01*
Y1610684D01*
X2279368Y1613601D01*
X2281551Y1616518D01*
G01X2293593Y1599018D02*
Y1610684D01*
G01Y1607476D02*
X2294248Y1608935D01*
X2295340Y1610101D01*
X2296868Y1610684D01*
X2298396Y1610101D01*
X2299488Y1608935D01*
X2300143Y1607476D01*
Y1599018D01*
G01Y1607476D02*
X2300798Y1608935D01*
X2301889Y1610101D01*
X2303418Y1610684D01*
X2304946Y1610101D01*
X2306038Y1608935D01*
X2306693Y1607185D01*
Y1599018D01*
G01X2317643Y1610684D02*
Y1599018D01*
G01Y1615351D02*
X2317206Y1615643D01*
Y1616226D01*
X2317643Y1616518D01*
X2318080Y1616226D01*
Y1615643D01*
X2317643Y1615351D01*
G01X2335143Y1599018D02*
Y1616518D01*
G01X2349368Y1601059D02*
X2350460Y1599893D01*
X2351988Y1599018D01*
X2353298D01*
X2354608Y1599601D01*
X2355481Y1600476D01*
X2355918Y1601642D01*
X2355700Y1603393D01*
X2354826Y1604268D01*
X2350896Y1606018D01*
X2350023Y1608060D01*
X2350460Y1609518D01*
X2351333Y1610393D01*
X2352643Y1610684D01*
X2353953Y1610393D01*
X2355263Y1609518D01*
G01X2371235Y1593185D02*
X2373418Y1596101D01*
X2374510Y1599018D01*
Y1610684D01*
X2373418Y1613601D01*
X2371235Y1616518D01*
G01X2259013Y1564368D02*
Y1581868D01*
X2250934Y1569326D01*
X2261852D01*
G01X2273893Y1563785D02*
X2273456Y1564076D01*
Y1564660D01*
X2273893Y1564951D01*
X2274330Y1564660D01*
Y1564076D01*
X2273893Y1563785D01*
G01X2290956Y1564368D02*
X2291393Y1568159D01*
X2292048Y1571368D01*
X2292921Y1574285D01*
X2294013Y1577493D01*
X2295760Y1581868D01*
X2287026D01*
G01X2304090Y1566992D02*
X2305399Y1565534D01*
X2306928Y1564660D01*
X2308893Y1564368D01*
X2310858Y1564951D01*
X2312386Y1566118D01*
X2313478Y1568159D01*
X2313696Y1570493D01*
X2313260Y1572826D01*
X2312168Y1574285D01*
X2310639Y1575451D01*
X2309111Y1575743D01*
X2307583Y1575451D01*
X2305618Y1574285D01*
X2306273Y1581868D01*
X2312168D01*
G01X2431393Y1616518D02*
Y1599018D01*
G01X2426371Y1616518D02*
X2436415D01*
G01X2448893Y1599018D02*
Y1606893D01*
X2444526Y1616518D01*
G01X2453260D02*
X2448893Y1606893D01*
G01X2462026Y1599018D02*
Y1616518D01*
X2467266D01*
X2469013Y1615643D01*
X2470323Y1613601D01*
X2470760Y1611268D01*
X2470323Y1608935D01*
X2469231Y1607185D01*
X2467266Y1606309D01*
X2462026D01*
G01X2488260Y1599018D02*
X2479526D01*
Y1616518D01*
X2488260D01*
G01X2484766Y1608060D02*
X2479526D01*
G01X2444308Y1566701D02*
X2446055Y1565243D01*
X2448020Y1564368D01*
X2449766D01*
X2451513Y1565243D01*
X2452823Y1566701D01*
X2453478Y1568743D01*
X2453041Y1570784D01*
X2451950Y1572535D01*
X2449985Y1573701D01*
X2447365Y1574285D01*
X2445836Y1575451D01*
X2445181Y1577493D01*
X2445618Y1579535D01*
X2446710Y1580993D01*
X2448238Y1581868D01*
X2449766D01*
X2451295Y1581285D01*
X2452605Y1579826D01*
G01X2470760Y1564368D02*
X2462026D01*
Y1581868D01*
X2470760D01*
G01X2467266Y1573410D02*
X2462026D01*
G01X2532026Y1599018D02*
Y1616518D01*
X2537485D01*
X2539231Y1615643D01*
X2540323Y1614476D01*
X2540760Y1612143D01*
X2540323Y1609809D01*
X2539013Y1608351D01*
X2537485Y1607476D01*
X2532026D01*
G01X2537485D02*
X2540760Y1599018D01*
G01X2550618Y1606893D02*
X2557605D01*
X2556950Y1608935D01*
X2555858Y1610101D01*
X2554330Y1610684D01*
X2552801Y1610393D01*
X2551491Y1609518D01*
X2550618Y1607476D01*
X2550181Y1605726D01*
Y1603976D01*
X2550618Y1602226D01*
X2551710Y1600476D01*
X2553020Y1599310D01*
X2554548Y1599018D01*
X2556076Y1599601D01*
X2557605Y1601351D01*
G01X2570083Y1599018D02*
Y1613893D01*
X2570520Y1615351D01*
X2571393Y1616226D01*
X2572703Y1616518D01*
X2574013Y1615935D01*
X2574668Y1614476D01*
G01X2572048Y1609518D02*
X2567681D01*
G01X2588893Y1598435D02*
X2588456Y1598726D01*
Y1599310D01*
X2588893Y1599601D01*
X2589330Y1599310D01*
Y1598726D01*
X2588893Y1598435D01*
G01X2619526Y1599018D02*
Y1616518D01*
X2624766D01*
X2626513Y1615643D01*
X2627823Y1613601D01*
X2628260Y1611268D01*
X2627823Y1608935D01*
X2626731Y1607185D01*
X2624766Y1606309D01*
X2619526D01*
G01X2641393Y1599018D02*
Y1616518D01*
G01X2662823Y1599018D02*
Y1610684D01*
G01Y1608643D02*
X2661950Y1609809D01*
X2660639Y1610393D01*
X2659111Y1610684D01*
X2657583Y1610101D01*
X2656273Y1608935D01*
X2655399Y1607185D01*
X2654963Y1604851D01*
X2655399Y1602518D01*
X2656273Y1600768D01*
X2657583Y1599601D01*
X2659111Y1599018D01*
X2660639Y1599310D01*
X2661950Y1600184D01*
X2662823Y1601351D01*
G01X2672681Y1599018D02*
Y1610684D01*
G01Y1607768D02*
X2673555Y1609226D01*
X2674865Y1610393D01*
X2676611Y1610684D01*
X2678139Y1610393D01*
X2679450Y1609226D01*
X2680105Y1607185D01*
Y1599018D01*
G01X2690618Y1606893D02*
X2697605D01*
X2696950Y1608935D01*
X2695858Y1610101D01*
X2694330Y1610684D01*
X2692801Y1610393D01*
X2691491Y1609518D01*
X2690618Y1607476D01*
X2690181Y1605726D01*
Y1603976D01*
X2690618Y1602226D01*
X2691710Y1600476D01*
X2693020Y1599310D01*
X2694548Y1599018D01*
X2696076Y1599601D01*
X2697605Y1601351D01*
G01X2575776Y1581868D02*
Y1564368D01*
X2584510D01*
G01X2600263D02*
Y1581868D01*
X2592184Y1569326D01*
X2603102D01*
G01X2611213Y1563785D02*
X2619073Y1581868D01*
G01X2628276D02*
Y1564368D01*
X2637010D01*
G01X2645995Y1571659D02*
X2647523Y1573701D01*
X2648833Y1574868D01*
X2650580Y1575451D01*
X2652108Y1574868D01*
X2653200Y1573701D01*
X2654073Y1571951D01*
X2654291Y1569910D01*
X2654073Y1568159D01*
X2653200Y1566409D01*
X2651889Y1564951D01*
X2650361Y1564368D01*
X2648615Y1564951D01*
X2647086Y1566701D01*
X2646213Y1569326D01*
X2645995Y1572243D01*
X2646431Y1576034D01*
X2647086Y1578077D01*
X2648178Y1580118D01*
X2649706Y1581576D01*
X2651235Y1581868D01*
X2652763Y1581285D01*
X2653855Y1579826D01*
G01X2811693Y1576034D02*
Y1564368D01*
G01Y1580701D02*
X2811256Y1580993D01*
Y1581576D01*
X2811693Y1581868D01*
X2812130Y1581576D01*
Y1580993D01*
X2811693Y1580701D01*
G01X2825918Y1566409D02*
X2827010Y1565243D01*
X2828538Y1564368D01*
X2829848D01*
X2831158Y1564951D01*
X2832031Y1565826D01*
X2832468Y1566992D01*
X2832250Y1568743D01*
X2831376Y1569618D01*
X2827446Y1571368D01*
X2826573Y1573410D01*
X2827010Y1574868D01*
X2827883Y1575743D01*
X2829193Y1576034D01*
X2830503Y1575743D01*
X2831813Y1574868D01*
G01X2859171Y1564368D02*
Y1581868D01*
X2869215Y1564368D01*
Y1581868D01*
G01X2881693Y1564368D02*
X2879946Y1564660D01*
X2878418Y1565826D01*
X2877108Y1567576D01*
X2876234Y1569618D01*
X2875798Y1571951D01*
Y1574285D01*
X2876234Y1576618D01*
X2877108Y1578660D01*
X2878418Y1580409D01*
X2879946Y1581576D01*
X2881693Y1581868D01*
X2883439Y1581576D01*
X2884968Y1580409D01*
X2886278Y1578660D01*
X2887152Y1576618D01*
X2887588Y1574285D01*
Y1571951D01*
X2887152Y1569618D01*
X2886278Y1567576D01*
X2884968Y1565826D01*
X2883439Y1564660D01*
X2881693Y1564368D01*
G01X2899193Y1581868D02*
Y1564368D01*
G01X2894171Y1581868D02*
X2904215D01*
G01X2930481Y1576034D02*
Y1567868D01*
X2931355Y1565826D01*
X2932665Y1564660D01*
X2934193Y1564368D01*
X2935721Y1564660D01*
X2937031Y1565826D01*
X2937905Y1567868D01*
G01Y1564368D02*
Y1576034D01*
G01X2948418Y1566409D02*
X2949510Y1565243D01*
X2951038Y1564368D01*
X2952348D01*
X2953658Y1564951D01*
X2954531Y1565826D01*
X2954968Y1566992D01*
X2954750Y1568743D01*
X2953876Y1569618D01*
X2949946Y1571368D01*
X2949073Y1573410D01*
X2949510Y1574868D01*
X2950383Y1575743D01*
X2951693Y1576034D01*
X2953003Y1575743D01*
X2954313Y1574868D01*
G01X2965918Y1572243D02*
X2972905D01*
X2972250Y1574285D01*
X2971158Y1575451D01*
X2969630Y1576034D01*
X2968101Y1575743D01*
X2966791Y1574868D01*
X2965918Y1572826D01*
X2965481Y1571076D01*
Y1569326D01*
X2965918Y1567576D01*
X2967010Y1565826D01*
X2968320Y1564660D01*
X2969848Y1564368D01*
X2971376Y1564951D01*
X2972905Y1566701D01*
G01X2990623Y1581868D02*
Y1564368D01*
G01Y1566992D02*
X2989750Y1565534D01*
X2988439Y1564660D01*
X2986911Y1564368D01*
X2985165Y1564951D01*
X2983855Y1566409D01*
X2982981Y1568159D01*
X2982763Y1570201D01*
X2982981Y1572243D01*
X2983855Y1573993D01*
X2985165Y1575451D01*
X2986911Y1576034D01*
X2988439Y1575743D01*
X2989531Y1575159D01*
X2990623Y1573993D01*
G01X2736890Y1598435D02*
X2746496Y1611268D01*
G01X2741693Y1613601D02*
Y1596101D01*
G01X2746496Y1598435D02*
X2736890Y1611268D01*
G01X2735143Y1604851D02*
X2748243D01*
G01X2773855D02*
X2779531D01*
G01X2806890Y1599018D02*
Y1616518D01*
X2811256D01*
X2813003Y1615643D01*
X2814313Y1614476D01*
X2815405Y1612727D01*
X2816278Y1610684D01*
X2816496Y1607768D01*
X2816278Y1604851D01*
X2815405Y1602809D01*
X2814313Y1601059D01*
X2813003Y1599893D01*
X2811256Y1599018D01*
X2806890D01*
G01X2825918Y1606893D02*
X2832905D01*
X2832250Y1608935D01*
X2831158Y1610101D01*
X2829630Y1610684D01*
X2828101Y1610393D01*
X2826791Y1609518D01*
X2825918Y1607476D01*
X2825481Y1605726D01*
Y1603976D01*
X2825918Y1602226D01*
X2827010Y1600476D01*
X2828320Y1599310D01*
X2829848Y1599018D01*
X2831376Y1599601D01*
X2832905Y1601351D01*
G01X2842981Y1599018D02*
Y1610684D01*
G01Y1607768D02*
X2843855Y1609226D01*
X2845165Y1610393D01*
X2846911Y1610684D01*
X2848439Y1610393D01*
X2849750Y1609226D01*
X2850405Y1607185D01*
Y1599018D01*
G01X2864193D02*
X2862883Y1599310D01*
X2861573Y1600476D01*
X2860699Y1602518D01*
X2860263Y1604851D01*
X2860699Y1607185D01*
X2861573Y1609226D01*
X2862883Y1610393D01*
X2864193Y1610684D01*
X2865503Y1610393D01*
X2866813Y1609226D01*
X2867686Y1607185D01*
X2867905Y1604851D01*
X2867686Y1602518D01*
X2866813Y1600476D01*
X2865503Y1599310D01*
X2864193Y1599018D01*
G01X2881693Y1616518D02*
Y1599018D01*
G01X2878636Y1610684D02*
X2884750D01*
G01X2895918Y1606893D02*
X2902905D01*
X2902250Y1608935D01*
X2901158Y1610101D01*
X2899630Y1610684D01*
X2898101Y1610393D01*
X2896791Y1609518D01*
X2895918Y1607476D01*
X2895481Y1605726D01*
Y1603976D01*
X2895918Y1602226D01*
X2897010Y1600476D01*
X2898320Y1599310D01*
X2899848Y1599018D01*
X2901376Y1599601D01*
X2902905Y1601351D01*
G01X2913418Y1601059D02*
X2914510Y1599893D01*
X2916038Y1599018D01*
X2917348D01*
X2918658Y1599601D01*
X2919531Y1600476D01*
X2919968Y1601642D01*
X2919750Y1603393D01*
X2918876Y1604268D01*
X2914946Y1606018D01*
X2914073Y1608060D01*
X2914510Y1609518D01*
X2915383Y1610393D01*
X2916693Y1610684D01*
X2918003Y1610393D01*
X2919313Y1609518D01*
G01X2951693Y1616518D02*
Y1599018D01*
G01X2948636Y1610684D02*
X2954750D01*
G01X2965481Y1599018D02*
Y1616518D01*
G01Y1608060D02*
X2966573Y1609518D01*
X2967665Y1610393D01*
X2969411Y1610684D01*
X2970721Y1610393D01*
X2972250Y1609226D01*
X2972905Y1607476D01*
Y1599018D01*
G01X2990623D02*
Y1610684D01*
G01Y1608643D02*
X2989750Y1609809D01*
X2988439Y1610393D01*
X2986911Y1610684D01*
X2985383Y1610101D01*
X2984073Y1608935D01*
X2983199Y1607185D01*
X2982763Y1604851D01*
X2983199Y1602518D01*
X2984073Y1600768D01*
X2985383Y1599601D01*
X2986911Y1599018D01*
X2988439Y1599310D01*
X2989750Y1600184D01*
X2990623Y1601351D01*
G01X3004193Y1616518D02*
Y1599018D01*
G01X3001136Y1610684D02*
X3007250D01*
G01X3039193Y1616518D02*
Y1599018D01*
G01X3036136Y1610684D02*
X3042250D01*
G01X3052981Y1599018D02*
Y1616518D01*
G01Y1608060D02*
X3054073Y1609518D01*
X3055165Y1610393D01*
X3056911Y1610684D01*
X3058221Y1610393D01*
X3059750Y1609226D01*
X3060405Y1607476D01*
Y1599018D01*
G01X3074193Y1610684D02*
Y1599018D01*
G01Y1615351D02*
X3073756Y1615643D01*
Y1616226D01*
X3074193Y1616518D01*
X3074630Y1616226D01*
Y1615643D01*
X3074193Y1615351D01*
G01X3088418Y1601059D02*
X3089510Y1599893D01*
X3091038Y1599018D01*
X3092348D01*
X3093658Y1599601D01*
X3094531Y1600476D01*
X3094968Y1601642D01*
X3094750Y1603393D01*
X3093876Y1604268D01*
X3089946Y1606018D01*
X3089073Y1608060D01*
X3089510Y1609518D01*
X3090383Y1610393D01*
X3091693Y1610684D01*
X3093003Y1610393D01*
X3094313Y1609518D01*
G01X3124073Y1616518D02*
X3129313D01*
G01X3126693D02*
Y1599018D01*
G01X3124073D02*
X3129313D01*
G01X3137643D02*
Y1610684D01*
G01Y1607476D02*
X3138298Y1608935D01*
X3139390Y1610101D01*
X3140918Y1610684D01*
X3142446Y1610101D01*
X3143538Y1608935D01*
X3144193Y1607476D01*
Y1599018D01*
G01Y1607476D02*
X3144848Y1608935D01*
X3145939Y1610101D01*
X3147468Y1610684D01*
X3148996Y1610101D01*
X3150088Y1608935D01*
X3150743Y1607185D01*
Y1599018D01*
G01X3157763Y1593185D02*
Y1610684D01*
G01Y1608060D02*
X3158855Y1609518D01*
X3159946Y1610393D01*
X3161693Y1610684D01*
X3163221Y1610393D01*
X3164750Y1608935D01*
X3165405Y1606893D01*
X3165623Y1604851D01*
X3165405Y1602809D01*
X3164750Y1600768D01*
X3163439Y1599601D01*
X3161693Y1599018D01*
X3160165Y1599310D01*
X3158636Y1600184D01*
X3157763Y1601351D01*
G01X3175918Y1606893D02*
X3182905D01*
X3182250Y1608935D01*
X3181158Y1610101D01*
X3179630Y1610684D01*
X3178101Y1610393D01*
X3176791Y1609518D01*
X3175918Y1607476D01*
X3175481Y1605726D01*
Y1603976D01*
X3175918Y1602226D01*
X3177010Y1600476D01*
X3178320Y1599310D01*
X3179848Y1599018D01*
X3181376Y1599601D01*
X3182905Y1601351D01*
G01X3200623Y1616518D02*
Y1599018D01*
G01Y1601642D02*
X3199750Y1600184D01*
X3198439Y1599310D01*
X3196911Y1599018D01*
X3195165Y1599601D01*
X3193855Y1601059D01*
X3192981Y1602809D01*
X3192763Y1604851D01*
X3192981Y1606893D01*
X3193855Y1608643D01*
X3195165Y1610101D01*
X3196911Y1610684D01*
X3198439Y1610393D01*
X3199531Y1609809D01*
X3200623Y1608643D01*
G01X3218123Y1599018D02*
Y1610684D01*
G01Y1608643D02*
X3217250Y1609809D01*
X3215939Y1610393D01*
X3214411Y1610684D01*
X3212883Y1610101D01*
X3211573Y1608935D01*
X3210699Y1607185D01*
X3210263Y1604851D01*
X3210699Y1602518D01*
X3211573Y1600768D01*
X3212883Y1599601D01*
X3214411Y1599018D01*
X3215939Y1599310D01*
X3217250Y1600184D01*
X3218123Y1601351D01*
G01X3227981Y1599018D02*
Y1610684D01*
G01Y1607768D02*
X3228855Y1609226D01*
X3230165Y1610393D01*
X3231911Y1610684D01*
X3233439Y1610393D01*
X3234750Y1609226D01*
X3235405Y1607185D01*
Y1599018D01*
G01X3252686Y1609226D02*
X3251158Y1610393D01*
X3249848Y1610684D01*
X3248101Y1610101D01*
X3246791Y1608935D01*
X3245918Y1606893D01*
X3245699Y1604851D01*
X3245918Y1602809D01*
X3246791Y1601059D01*
X3248101Y1599601D01*
X3249848Y1599018D01*
X3251376Y1599601D01*
X3252686Y1600768D01*
G01X3263418Y1606893D02*
X3270405D01*
X3269750Y1608935D01*
X3268658Y1610101D01*
X3267130Y1610684D01*
X3265601Y1610393D01*
X3264291Y1609518D01*
X3263418Y1607476D01*
X3262981Y1605726D01*
Y1603976D01*
X3263418Y1602226D01*
X3264510Y1600476D01*
X3265820Y1599310D01*
X3267348Y1599018D01*
X3268876Y1599601D01*
X3270405Y1601351D01*
G01X0Y-137756D02*
G03X15000Y-152756I15000J0D01*
G01X0Y-137756D02*
G03X15000Y-152756I15000J0D01*
G01X0Y-11811D02*
Y-137756D01*
G01Y-11811D02*
Y-137756D01*
G01X854331Y-152756D02*
X15000D01*
G01X854331D02*
X15000D01*
G01X23622Y-7874D02*
G03Y0I0J3937D01*
G01Y-7874D02*
G03Y0I0J3937D01*
G01X0Y3937D02*
G03X3937Y0I3937J0D01*
G01Y-7874D02*
X23622D01*
G01X0Y3937D02*
G03X3937Y0I3937J0D01*
G01Y-7874D02*
X23622D01*
G01X3937D02*
G03X0Y-11811I0J-3937D01*
G01X3937Y-7874D02*
G03X0Y-11811I0J-3937D01*
G01X3937Y0D02*
X397638D01*
G01X3937D02*
X397638D01*
G01X0Y1370866D02*
Y3937D01*
G01Y1370866D02*
Y3937D01*
G01X3937Y1374803D02*
G03X0Y1370866I0J-3937D01*
G01X3937Y1374803D02*
G03X0Y1370866I0J-3937D01*
G01X23622Y1374803D02*
G03Y1382677I0J3937D01*
G01Y1374803D02*
G03Y1382677I0J3937D01*
G01X3937D02*
X23622D01*
G01X0Y1386614D02*
G03X3937Y1382677I3937J0D01*
G01D02*
X23622D01*
G01X0Y1386614D02*
G03X3937Y1382677I3937J0D01*
G01Y1374803D02*
X746850D01*
G01D02*
X3937D01*
G01X0Y1386614D02*
Y1643268D01*
G01Y1386614D02*
Y1643268D01*
G01X15000Y1658268D02*
G03X0Y1643268I0J-15000D01*
G01X15000Y1658268D02*
G03X0Y1643268I0J-15000D01*
G01X775591Y1658268D02*
X15000D01*
G01X775591D02*
X15000D01*
G01X54331Y-7874D02*
X323228D01*
G01X54331D02*
X323228D01*
G01X54331Y0D02*
G03Y-7874I0J-3937D01*
G01Y0D02*
G03Y-7874I0J-3937D01*
G01Y1382677D02*
G03Y1374803I0J-3937D01*
G01Y1382677D02*
G03Y1374803I0J-3937D01*
G01Y1382677D02*
X353740D01*
G01X54331D02*
X353740D01*
G01X114295Y378885D02*
G03X148106I16905J-13531D01*
G01X114295D02*
G03X148106I16905J-13531D01*
G01X114295D02*
G03X121220Y392016I-30737J24602D01*
G01X114295Y378885D02*
G03X121220Y392016I-30737J24602D01*
G01X114295Y831641D02*
G03X121220Y844772I-30737J24601D01*
G01X114295Y831641D02*
G03X121220Y844772I-30737J24602D01*
G01X114295Y831641D02*
G03X148106I16905J-13531D01*
G01X114295D02*
G03X148106I16905J-13531D01*
G01X114295Y1284397D02*
G03X148106I16905J-13531D01*
G01X114295D02*
G03X148106I16905J-13531D01*
G01X114295D02*
G03X121220Y1297528I-30737J24601D01*
G01X114295Y1284397D02*
G03X121220Y1297528I-30737J24602D01*
G01X141181Y392016D02*
G03X121220I-9980J-3039D01*
G01X141181D02*
G03X148106Y378885I37662J11471D01*
G01X141181Y392016D02*
G03X121220I-9980J-3039D01*
G01X141181D02*
G03X148106Y378885I37662J11471D01*
G01X141181Y844772D02*
G03X148106Y831641I37662J11471D01*
G01X141181Y844772D02*
G03X148106Y831641I37662J11471D01*
G01X141181Y844772D02*
G03X121220I-9980J-3040D01*
G01X141181D02*
G03X121220I-9980J-3039D01*
G01X141181Y1297528D02*
G03X121220I-9980J-3040D01*
G01X141181D02*
G03X148106Y1284397I37662J11471D01*
G01X141181Y1297528D02*
G03X121220I-9980J-3040D01*
G01X141181D02*
G03X148106Y1284397I37662J11471D01*
G01X323228Y-7874D02*
G03Y0I0J3937D01*
G01Y-7874D02*
G03Y0I0J3937D01*
G01X362598D02*
G03Y-7874I0J-3937D01*
G01Y0D02*
G03Y-7874I0J-3937D01*
G01X362327Y378885D02*
G03X396138I16905J-13531D01*
G01X362327D02*
G03X396138I16905J-13531D01*
G01X362327D02*
G03X369252Y392016I-30737J24602D01*
G01X362327Y378885D02*
G03X369252Y392016I-30737J24602D01*
G01X362327Y831641D02*
G03X369252Y844772I-30737J24602D01*
G01X362327Y831641D02*
G03X369252Y844772I-30737J24602D01*
G01X362327Y831641D02*
G03X396138I16905J-13531D01*
G01X362327D02*
G03X396138I16905J-13531D01*
G01X362327Y1284397D02*
G03X396138I16905J-13531D01*
G01X362327D02*
G03X396138I16905J-13531D01*
G01X362327D02*
G03X369252Y1297528I-30737J24602D01*
G01X362327Y1284397D02*
G03X369252Y1297528I-30737J24602D01*
G01X353740Y1374803D02*
G03Y1382677I0J3937D01*
G01Y1374803D02*
G03Y1382677I0J3937D01*
G01X401575Y3937D02*
Y55118D01*
G01X397638Y0D02*
G03X401575Y3937I0J3937D01*
G01X409449D02*
Y51181D01*
G01X397638Y-7874D02*
G03X409449Y3937I0J11811D01*
G01X397638Y0D02*
G03X401575Y3937I0J3937D01*
G01D02*
Y55118D01*
G01X409449Y3937D02*
Y51181D01*
G01X397638Y-7874D02*
G03X409449Y3937I0J11811D01*
G01X362598Y-7874D02*
X397638D01*
G01X362598D02*
X397638D01*
G01X405512Y59055D02*
G03X401575Y55118I0J-3937D01*
G01X405512Y59055D02*
G03X401575Y55118I0J-3937D01*
G01X405512Y59055D02*
X586614D01*
G01X409449Y51181D02*
X582677D01*
G01X405512Y59055D02*
X586614D01*
G01X409449Y51181D02*
X582677D01*
G01X389213Y392016D02*
G03X396138Y378885I37662J11471D01*
G01X389213Y392016D02*
G03X396138Y378885I37662J11471D01*
G01X389213Y392016D02*
G03X369252I-9981J-3039D01*
G01X389213D02*
G03X369252I-9981J-3039D01*
G01X389213Y844772D02*
G03X396138Y831641I37662J11471D01*
G01X389213Y844772D02*
G03X396138Y831641I37662J11471D01*
G01X389213Y844772D02*
G03X369252I-9981J-3040D01*
G01X389213D02*
G03X369252I-9981J-3039D01*
G01X389213Y1297528D02*
G03X396138Y1284397I37662J11471D01*
G01X389213Y1297528D02*
G03X396138Y1284397I37662J11471D01*
G01X389213Y1297528D02*
G03X369252I-9981J-3040D01*
G01X389213D02*
G03X369252I-9981J-3040D01*
G01X393110Y1382677D02*
G03Y1374803I0J-3937D01*
G01Y1382677D02*
X692520D01*
G01X393110D02*
X692520D01*
G01X393110D02*
G03Y1374803I0J-3937D01*
G01X523327Y829921D02*
G03X483169I-20079J0D01*
G01X523327D02*
G03I-20079J0D01*
G01X483169D02*
G03X523327I20079J0D01*
G01X594488Y-7874D02*
X628765D01*
G01X594488D02*
X628765D01*
G01X590551Y55118D02*
Y3937D01*
G01D02*
G03X594488Y0I3937J0D01*
G01X582677Y51181D02*
Y3937D01*
G01D02*
G03X594488Y-7874I11811J0D01*
G01X590551Y55118D02*
Y3937D01*
G01D02*
G03X594488Y0I3937J0D01*
G01X582677Y51181D02*
Y3937D01*
G01D02*
G03X594488Y-7874I11811J0D01*
G01Y0D02*
X783465D01*
G01X594488D02*
X783465D01*
G01X590551Y55118D02*
G03X586614Y59055I-3937J0D01*
G01X590551Y55118D02*
G03X586614Y59055I-3937J0D01*
G01X628765Y-7874D02*
G03Y0I0J3937D01*
G01Y-7874D02*
G03Y0I0J3937D01*
G01X610358Y378885D02*
G03X644169I16906J-13531D01*
G01X610358D02*
G03X644169I16906J-13531D01*
G01X637244Y392016D02*
G03X644169Y378885I37662J11471D01*
G01X637244Y392016D02*
G03X644169Y378885I37662J11471D01*
G01X637244Y392016D02*
G03X617283I-9980J-3039D01*
G01X637244D02*
G03X617283I-9980J-3039D01*
G01X610358Y378885D02*
G03X617283Y392016I-30737J24602D01*
G01X610358Y378885D02*
G03X617283Y392016I-30737J24602D01*
G01X637244Y844772D02*
G03X644169Y831641I37662J11471D01*
G01X637244Y844772D02*
G03X644169Y831641I37662J11471D01*
G01X610358D02*
G03X617283Y844772I-30737J24601D01*
G01X610358Y831641D02*
G03X617283Y844772I-30737J24602D01*
G01X610358Y831641D02*
G03X644169I16906J-13531D01*
G01X610358D02*
G03X644169I16906J-13531D01*
G01X637244Y844772D02*
G03X617283I-9980J-3040D01*
G01X637244D02*
G03X617283I-9980J-3039D01*
G01X610358Y1284397D02*
G03X644169I16906J-13531D01*
G01X610358D02*
G03X644169I16906J-13531D01*
G01X637244Y1297528D02*
G03X644169Y1284397I37662J11471D01*
G01X637244Y1297528D02*
G03X644169Y1284397I37662J11471D01*
G01X610358D02*
G03X617283Y1297528I-30737J24601D01*
G01X637244D02*
G03X617283I-9980J-3040D01*
G01X610358Y1284397D02*
G03X617283Y1297528I-30737J24602D01*
G01X637244D02*
G03X617283I-9980J-3040D01*
G01X659474Y0D02*
G03Y-7874I0J-3937D01*
G01Y0D02*
G03Y-7874I0J-3937D01*
G01D02*
X780203D01*
G01X659474D02*
X780203D01*
G01X692520Y1374803D02*
G03Y1382677I0J3937D01*
G01Y1374803D02*
G03Y1382677I0J3937D01*
G01X746850Y1374803D02*
G03X750787Y1378740I0J3937D01*
G01X746850Y1374803D02*
G03X750787Y1378740I0J3937D01*
G01X723228Y1382677D02*
G03Y1374803I0J-3937D01*
G01Y1382677D02*
X742913D01*
G01X723228D02*
X742913D01*
G01X723228D02*
G03Y1374803I0J-3937D01*
G01X742913Y1464567D02*
Y1382677D01*
G01Y1464567D02*
Y1382677D01*
G01X754724Y1476378D02*
G03X742913Y1464567I0J-11811D01*
G01X754724Y1476378D02*
G03X742913Y1464567I0J-11811D01*
G01X862205Y-7874D02*
X791339D01*
G01X787402Y-3937D02*
G03X791339Y-7874I3937J0D01*
G01X787402Y-3937D02*
G03X791339Y-7874I3937J0D01*
G01D02*
X862205D01*
G01X858268Y-15748D02*
X791339D01*
G01X858268D02*
X791339D01*
G01X787402Y-3937D02*
G03X783465Y0I-3937J0D01*
G01X787402Y-3937D02*
G03X783465Y0I-3937J0D01*
G01X780203Y-7874D02*
G03X791339Y-15748I11136J3937D01*
G01X780203Y-7874D02*
G03X791339Y-15748I11136J3937D01*
G01X779551Y264712D02*
G03X813362I16905J-13531D01*
G01X779551D02*
G03X813362I16905J-13531D01*
G01X779551D02*
G03X786476Y277843I-30737J24601D01*
G01X806437D02*
G03X786476I-9981J-3040D01*
G01X779551Y264712D02*
G03X786476Y277843I-30737J24602D01*
G01X806437D02*
G03X786476I-9981J-3040D01*
G01X779551Y737153D02*
G03X786476Y750284I-30737J24601D01*
G01X779551Y737154D02*
G03X786476Y750284I-30736J24602D01*
G01X779551Y737153D02*
G03X813362I16905J-13531D01*
G01X779551D02*
G03X813362I16905J-13531D01*
G01X806437Y750284D02*
G03X786476I-9981J-3040D01*
G01X806437D02*
G03X786476I-9981J-3040D01*
G01X750787Y1464567D02*
Y1378740D01*
G01Y1464567D02*
Y1378740D01*
G01X783465Y1468504D02*
G03X787402Y1472441I0J3937D01*
G01X783465Y1468504D02*
G03X787402Y1472441I0J3937D01*
G01X783465Y1468504D02*
X754724D01*
G01D02*
G03X750787Y1464567I0J-3937D01*
G01X783465Y1468504D02*
X754724D01*
G01D02*
G03X750787Y1464567I0J-3937D01*
G01X779528Y1476378D02*
X754724D01*
G01X779528D02*
X754724D01*
G01X787402Y1654331D02*
Y1472441D01*
G01X779528Y1596063D02*
Y1476378D01*
G01X787402Y1654331D02*
Y1472441D01*
G01X779528Y1596063D02*
Y1476378D01*
G01X787402Y1596063D02*
G03X779528I-3937J0D01*
G01X787402D02*
G03X779528I-3937J0D01*
G01X1216535Y1658268D02*
X791339D01*
G01D02*
G03X787402Y1654331I0J-3937D01*
G01X779528D02*
G03X775591Y1658268I-3937J0D01*
G01X1216535D02*
X791339D01*
G01D02*
G03X787402Y1654331I0J-3937D01*
G01X779528D02*
G03X775591Y1658268I-3937J0D01*
G01X779528Y1654331D02*
Y1626772D01*
G01D02*
G03X787402I3937J0D01*
G01X779528Y1654331D02*
Y1626772D01*
G01D02*
G03X787402I3937J0D01*
G01X806437Y277843D02*
G03X813362Y264712I37662J11471D01*
G01X806437Y277843D02*
G03X813362Y264712I37662J11471D01*
G01X806437Y750284D02*
G03X813362Y737153I37662J11471D01*
G01X806437Y750284D02*
G03X813362Y737154I37661J11472D01*
G01X866142Y-148819D02*
Y-11811D01*
G01Y-148819D02*
G03X870079Y-152756I3937J0D01*
G01X866142Y-11811D02*
Y-148819D01*
G01D02*
G03X870079Y-152756I3937J0D01*
G01X866142Y-129134D02*
G03X858268I-3937J0D01*
G01X866142D02*
G03X858268I-3937J0D01*
G01Y-148819D02*
Y-129134D01*
G01X854331Y-152756D02*
G03X858268Y-148819I0J3937D01*
G01D02*
Y-129134D01*
G01X854331Y-152756D02*
G03X858268Y-148819I0J3937D01*
G01X1177165Y-152756D02*
X870079D01*
G01D02*
X1177165D01*
G01X858268Y-98425D02*
Y-15748D01*
G01Y-98425D02*
Y-15748D01*
G01Y-98425D02*
G03X866142I3937J0D01*
G01X858268D02*
G03X866142I3937J0D01*
G01Y-11811D02*
G03X862205Y-7874I-3937J0D01*
G01X866142Y-11811D02*
G03X862205Y-7874I-3937J0D01*
G01X927032Y-57820D02*
G03X962731I17850J-12259D01*
G01X927032Y-57821D02*
G03X962732I17850J-12258D01*
G01X927032Y-57820D02*
G03X935199Y-42571I-64908J44575D01*
G01X954565D02*
G03X935199I-9683J-3885D01*
G01X927032Y-57821D02*
G03X935199Y-42571I-64909J44573D01*
G01X954564D02*
G03X935199I-9682J-3885D01*
G01X944512Y1089122D02*
G03X978323I16905J-13531D01*
G01X944512Y1089121D02*
G03X978323I16905J-13531D01*
G01X944512Y1431641D02*
G03X978323I16905J-13531D01*
G01X944512D02*
G03X978323I16905J-13531D01*
G01X954565Y-42571D02*
G03X962731Y-57820I73077J29322D01*
G01X954564Y-42570D02*
G03X962732Y-57821I73076J29324D01*
G01X971398Y1102252D02*
G03X978323Y1089122I37661J11472D01*
G01X971398Y1102252D02*
G03X978323Y1089121I37662J11471D01*
G01X971398Y1102252D02*
G03X951437I-9980J-3039D01*
G01X971398D02*
G03X951437I-9980J-3039D01*
G01X944512Y1089122D02*
G03X951437Y1102252I-30737J24602D01*
G01X944512Y1089121D02*
G03X951437Y1102252I-30737J24602D01*
G01X971398Y1444772D02*
G03X978323Y1431641I37662J11471D01*
G01X971398Y1444772D02*
G03X978323Y1431641I37662J11471D01*
G01X971398Y1444772D02*
G03X951437I-9980J-3040D01*
G01X944512Y1431641D02*
G03X951437Y1444772I-30737J24602D01*
G01X944512Y1431641D02*
G03X951437Y1444772I-30737J24602D01*
G01X971398D02*
G03X951437I-9980J-3039D01*
G01X1181102Y-148819D02*
Y-3937D01*
G01X1177165Y-152756D02*
G03X1181102Y-148819I0J3937D01*
G01X1177165Y-152756D02*
G03X1181102Y-148819I0J3937D01*
G01D02*
Y-3937D01*
G01Y-94488D02*
G03X1188976I3937J0D01*
G01X1181102D02*
G03X1188976I3937J0D01*
G01Y-125197D02*
G03X1181102I-3937J0D01*
G01X1188976D02*
G03X1181102I-3937J0D01*
G01X1185039Y0D02*
G03X1181102Y-3937I0J-3937D01*
G01X1185039Y0D02*
G03X1181102Y-3937I0J-3937D01*
G01X1164984Y557626D02*
G03X1198795I16906J-13531D01*
G01X1164984Y557625D02*
G03X1198795I16906J-13531D01*
G01X1191870Y570756D02*
G03X1171909I-9980J-3039D01*
G01X1191870D02*
G03X1171909I-9980J-3039D01*
G01X1164984Y557626D02*
G03X1171909Y570756I-30736J24602D01*
G01X1164984Y557625D02*
G03X1171909Y570756I-30737J24602D01*
G01X1164984Y971011D02*
G03X1198795I16906J-13531D01*
G01X1164984D02*
G03X1198795I16906J-13531D01*
G01X1191870Y984142D02*
G03X1171909I-9980J-3040D01*
G01X1191870D02*
G03X1171909I-9980J-3039D01*
G01X1164984Y971011D02*
G03X1171909Y984142I-30737J24602D01*
G01X1164984Y971011D02*
G03X1171909Y984142I-30737J24602D01*
G01X1164173Y1378740D02*
Y1468504D01*
G01X1930906Y1374803D02*
X1168110D01*
G01X1164173Y1378740D02*
G03X1168110Y1374803I3937J0D01*
G01X1172047Y1382677D02*
Y1464567D01*
G01X1195669Y1382677D02*
X1172047D01*
G01X1930906Y1374803D02*
X1168110D01*
G01X1164173Y1378740D02*
G03X1168110Y1374804I3937J1D01*
G01X1164173Y1378740D02*
Y1468504D01*
G01X1172047Y1382677D02*
Y1464567D01*
G01X1195669Y1382677D02*
X1172047D01*
G01X1168110Y1472441D02*
G03X1164173Y1468504I0J-3937D01*
G01X1168110Y1472441D02*
G03X1164173Y1468504I0J-3937D01*
G01X1172047Y1464567D02*
X1216535D01*
G01X1172047D02*
X1216535D01*
G01X1168110Y1472441D02*
X1216535D01*
G01X1168110D02*
X1216535D01*
G01X1164984Y1561563D02*
G03X1171909Y1574693I-30736J24602D01*
G01X1164984Y1561562D02*
G03X1171909Y1574693I-30737J24602D01*
G01X1164984Y1561563D02*
G03X1198795I16906J-13531D01*
G01X1164984Y1561562D02*
G03X1198795I16906J-13531D01*
G01X1191870Y1574693D02*
G03X1171909I-9980J-3039D01*
G01X1191870D02*
G03X1171909I-9980J-3039D01*
G01X1188976Y-148819D02*
Y-125197D01*
G01Y-148819D02*
G03X1192913Y-152756I3937J0D01*
G01X1188976Y-148819D02*
Y-125197D01*
G01Y-148819D02*
G03X1192913Y-152756I3937J0D01*
G01D02*
X1919843D01*
G01X1192913D02*
X1919843D01*
G01X1188976Y-94488D02*
Y-7874D01*
G01Y-94488D02*
Y-7874D01*
G01X1185039Y0D02*
X1366142D01*
G01X1188976Y-7874D02*
X1315748D01*
G01X1185039Y0D02*
X1366142D01*
G01X1188976Y-7874D02*
X1315748D01*
G01X1191870Y570756D02*
G03X1198795Y557626I37662J11472D01*
G01X1191870Y570756D02*
G03X1198795Y557626I37662J11472D01*
G01X1191870Y984142D02*
G03X1198795Y971011I37662J11471D01*
G01X1191870Y984142D02*
G03X1198795Y971011I37662J11471D01*
G01X1524606Y1382677D02*
X1226378D01*
G01X1524606D02*
X1226378D01*
G01X1195669Y1374803D02*
G03Y1382677I0J3937D01*
G01X1226378D02*
G03Y1374803I0J-3937D01*
G01X1195669D02*
G03Y1382677I0J3937D01*
G01X1226378D02*
G03Y1374803I0J-3937D01*
G01X1216535Y1464567D02*
G03X1228346Y1476378I0J11811D01*
G01X1216535Y1464567D02*
G03X1228346Y1476378I0J11811D01*
G01Y1592126D02*
Y1476378D01*
G01Y1592126D02*
Y1476378D01*
G01X1220472Y1654331D02*
Y1476378D01*
G01X1216535Y1472441D02*
G03X1220472Y1476378I0J3937D01*
G01X1216535Y1472441D02*
G03X1220472Y1476378I0J3937D01*
G01D02*
Y1654331D01*
G01X1191870Y1574693D02*
G03X1198795Y1561563I37662J11472D01*
G01X1191870Y1574693D02*
G03X1198795Y1561562I37662J11471D01*
G01X1228346Y1592126D02*
G03X1220472I-3937J0D01*
G01X1228346D02*
G03X1220472I-3937J0D01*
G01X1232283Y1658268D02*
X1442382D01*
G01X1232283D02*
G03X1228346Y1654331I0J-3937D01*
G01X1232283Y1658268D02*
X1442382D01*
G01X1232283D02*
G03X1228346Y1654331I0J-3937D01*
G01D02*
Y1622835D01*
G01Y1654331D02*
Y1622835D01*
G01X1220472Y1654331D02*
G03X1216535Y1658268I-3937J0D01*
G01X1220472Y1654331D02*
G03X1216535Y1658268I-3937J0D01*
G01X1220472Y1622835D02*
G03X1228346I3937J0D01*
G01X1220472D02*
G03X1228346I3937J0D01*
G01X1284965Y378885D02*
G03X1318776I16906J-13531D01*
G01X1284965D02*
G03X1318775I16905J-13531D01*
G01X1284965Y831641D02*
G03X1318776I16906J-13531D01*
G01X1284965D02*
G03X1318775I16905J-13531D01*
G01X1284965Y1284397D02*
G03X1318776I16906J-13531D01*
G01X1284965D02*
G03X1318775I16905J-13531D01*
G01X1315748Y-7874D02*
G03Y0I0J3937D01*
G01Y-7874D02*
G03Y0I0J3937D01*
G01X1311850Y392016D02*
G03X1291890I-9980J-3040D01*
G01X1311850D02*
G03X1318776Y378885I37662J11473D01*
G01X1311851Y392016D02*
G03X1291890I-9980J-3039D01*
G01X1311851D02*
G03X1318775Y378885I37663J11469D01*
G01X1284965D02*
G03X1291890Y392016I-30737J24602D01*
G01X1284965Y378885D02*
G03X1291890Y392016I-30737J24602D01*
G01X1284965Y831641D02*
G03X1291890Y844772I-30737J24602D01*
G01X1311850D02*
G03X1318776Y831641I37662J11473D01*
G01X1284965D02*
G03X1291890Y844772I-30737J24602D01*
G01X1311851D02*
G03X1318775Y831641I37663J11469D01*
G01X1311850Y844772D02*
G03X1291890I-9980J-3040D01*
G01X1311851D02*
G03X1291890I-9980J-3039D01*
G01X1284965Y1284397D02*
G03X1291890Y1297528I-30737J24602D01*
G01X1311850D02*
G03X1291890I-9980J-3040D01*
G01X1311850D02*
G03X1318776Y1284397I37661J11473D01*
G01X1284965D02*
G03X1291890Y1297528I-30737J24602D01*
G01X1311851D02*
G03X1291890I-9980J-3040D01*
G01X1311851D02*
G03X1318775Y1284397I37663J11469D01*
G01X1377953Y3937D02*
Y51181D01*
G01Y3937D02*
Y51181D01*
G01X1370079Y3937D02*
Y55118D01*
G01X1366142Y0D02*
G03X1370079Y3937I0J3937D01*
G01X1366142Y-7874D02*
G03X1377953Y3937I0J11811D01*
G01X1346457Y-7874D02*
X1366142D01*
G01Y0D02*
G03X1370079Y3937I0J3937D01*
G01D02*
Y55118D01*
G01X1346457Y-7874D02*
X1366142D01*
G01D02*
G03X1377953Y3937I0J11811D01*
G01X1346457Y0D02*
G03Y-7874I0J-3937D01*
G01Y0D02*
G03Y-7874I0J-3937D01*
G01X1374016Y59055D02*
G03X1370079Y55118I0J-3937D01*
G01X1374016Y59056D02*
G03X1370079Y55118I0J-3937D01*
G01X1374016Y59055D02*
X1555118D01*
G01X1377953Y51181D02*
X1551181D01*
G01X1374016Y59055D02*
X1555118D01*
G01X1377953Y51181D02*
X1551181D01*
G01X1442382Y1658268D02*
G03X1450256I3937J0D01*
G01X1442382D02*
G03X1450256I3937J0D01*
G01D02*
X1919843D01*
G01X1450256D02*
X1919843D01*
G01X1562992Y0D02*
X1930906D01*
G01X1559055Y55118D02*
Y3937D01*
G01D02*
G03X1562992Y0I3937J0D01*
G01Y-7874D02*
X1593701D01*
G01X1559055Y55118D02*
Y3937D01*
G01D02*
G03X1562992Y0I3937J0D01*
G01D02*
X1930906D01*
G01X1562992Y-7874D02*
X1593701D01*
G01X1551181Y51181D02*
Y3937D01*
G01D02*
G03X1562992Y-7874I11811J0D01*
G01X1551181Y51181D02*
Y3937D01*
G01D02*
G03X1562992Y-7874I11811J0D01*
G01X1559055Y55118D02*
G03X1555118Y59055I-3937J0D01*
G01X1559055Y55118D02*
G03X1555118Y59055I-3937J0D01*
G01X1532996Y378885D02*
G03X1566807I16906J-13531D01*
G01X1532996D02*
G03X1566807I16906J-13531D01*
G01X1559882Y392016D02*
G03X1566807Y378885I37662J11471D01*
G01X1559882Y392016D02*
G03X1566807Y378885I37662J11471D01*
G01X1559882Y392016D02*
G03X1539921I-9980J-3039D01*
G01X1559882D02*
G03X1539921I-9980J-3039D01*
G01X1532996Y378885D02*
G03X1539921Y392016I-30737J24602D01*
G01X1532996Y378885D02*
G03X1539921Y392016I-30737J24602D01*
G01X1559882Y844772D02*
G03X1566807Y831641I37662J11471D01*
G01X1559882Y844772D02*
G03X1566807Y831641I37662J11471D01*
G01X1532996D02*
G03X1539921Y844772I-30737J24602D01*
G01X1532996Y831641D02*
G03X1539921Y844772I-30737J24602D01*
G01X1532996Y831641D02*
G03X1566807I16906J-13531D01*
G01X1532996D02*
G03X1566807I16906J-13531D01*
G01X1559882Y844772D02*
G03X1539921I-9980J-3040D01*
G01X1559882D02*
G03X1539921I-9980J-3039D01*
G01X1532996Y1284397D02*
G03X1566807I16906J-13531D01*
G01X1532996D02*
G03X1566807I16906J-13531D01*
G01X1559882Y1297528D02*
G03X1566807Y1284397I37662J11471D01*
G01X1559882Y1297528D02*
G03X1566807Y1284397I37662J11471D01*
G01X1559882Y1297528D02*
G03X1539921I-9980J-3040D01*
G01X1532996Y1284397D02*
G03X1539921Y1297528I-30737J24602D01*
G01X1532996Y1284397D02*
G03X1539921Y1297528I-30737J24602D01*
G01X1559882D02*
G03X1539921I-9980J-3040D01*
G01X1563976Y1382677D02*
G03Y1374803I0J-3937D01*
G01Y1382677D02*
G03Y1374803I0J-3937D01*
G01X1524606D02*
G03Y1382677I0J3937D01*
G01Y1374803D02*
G03Y1382677I0J3937D01*
G01X1864567D02*
X1563976D01*
G01X1864567D02*
X1563976D01*
G01X1593701Y-7874D02*
G03Y0I0J3937D01*
G01Y-7874D02*
G03Y0I0J3937D01*
G01X1633071D02*
G03Y-7874I0J-3937D01*
G01D02*
X1880512D01*
G01X1633071D02*
X1880512D01*
G01X1633071Y0D02*
G03Y-7874I0J-3937D01*
G01X1693996Y829921D02*
G03X1653839I-20078J0D01*
G01X1693996D02*
G03I-20079J0D01*
G01X1653839D02*
G03X1693996I20078J0D01*
G01X1781028Y378885D02*
G03X1814839I16906J-13531D01*
G01X1781028D02*
G03X1814838I16905J-13531D01*
G01X1807913Y392016D02*
G03X1814839Y378885I37662J11473D01*
G01X1807914Y392016D02*
G03X1814838Y378885I37663J11469D01*
G01X1807913Y392016D02*
G03X1787953I-9980J-3040D01*
G01X1807914D02*
G03X1787953I-9980J-3039D01*
G01X1781028Y378885D02*
G03X1787953Y392016I-30737J24602D01*
G01X1781028Y378885D02*
G03X1787953Y392016I-30737J24602D01*
G01X1807913Y844772D02*
G03X1814839Y831641I37662J11473D01*
G01X1807914Y844772D02*
G03X1814838Y831641I37663J11469D01*
G01X1781028D02*
G03X1787953Y844772I-30737J24602D01*
G01X1781028Y831641D02*
G03X1787953Y844772I-30737J24602D01*
G01X1781028Y831641D02*
G03X1814839I16906J-13531D01*
G01X1781028D02*
G03X1814838I16905J-13531D01*
G01X1807913Y844772D02*
G03X1787953I-9980J-3040D01*
G01X1807914D02*
G03X1787953I-9980J-3039D01*
G01X1781028Y1284397D02*
G03X1814839I16906J-13531D01*
G01X1781028D02*
G03X1814838I16905J-13531D01*
G01X1807913Y1297528D02*
G03X1814839Y1284397I37661J11473D01*
G01X1807914Y1297528D02*
G03X1814838Y1284397I37663J11469D01*
G01X1807913Y1297528D02*
G03X1787953I-9980J-3040D01*
G01X1781028Y1284397D02*
G03X1787953Y1297528I-30737J24602D01*
G01X1781028Y1284397D02*
G03X1787953Y1297528I-30737J24602D01*
G01X1807914D02*
G03X1787953I-9980J-3040D01*
G01X1911220Y0D02*
G03Y-7874I0J-3937D01*
G01Y0D02*
G03Y-7874I0J-3937D01*
G01X1880512D02*
G03Y0I0J3937D01*
G01Y-7874D02*
G03Y0I0J3937D01*
G01X1930906Y1382677D02*
X1895276D01*
G01D02*
G03Y1374803I0J-3937D01*
G01X1930906Y1382677D02*
X1895276D01*
G01D02*
G03Y1374803I0J-3937D01*
G01X1864567D02*
G03Y1382677I0J3937D01*
G01Y1374803D02*
G03Y1382677I0J3937D01*
G01X1919843Y-152756D02*
G03X1934843Y-137756I0J15000D01*
G01X1919843Y-152756D02*
G03X1934843Y-137756I0J15000D01*
G01Y-11811D02*
Y-137756D01*
G01Y-11811D02*
Y-137756D01*
G01X1930906Y0D02*
G03X1934843Y3937I0J3937D01*
G01X1930906Y0D02*
G03X1934843Y3937I0J3937D01*
G01Y-11811D02*
G03X1930906Y-7874I-3937J0D01*
G01X1934843Y-11811D02*
G03X1930906Y-7874I-3937J0D01*
G01X1911220D02*
X1930906D01*
G01X1911220D02*
X1930906D01*
G01X1934843Y1370866D02*
Y3937D01*
G01D02*
Y1370866D01*
G01D02*
G03X1930906Y1374803I-3937J0D01*
G01X1934843Y1370866D02*
G03X1930906Y1374803I-3937J0D01*
G01Y1382677D02*
G03X1934843Y1386614I0J3937D01*
G01X1930906Y1382677D02*
G03X1934843Y1386614I0J3937D01*
G01D02*
Y1643268D01*
G01Y1386614D02*
Y1643268D01*
G01D02*
G03X1919843Y1658268I-15000J0D01*
G01X1934843Y1643268D02*
G03X1919843Y1658268I-15000J0D01*
G54D12*
G01X22298Y536902D02*
X24900Y534300D01*
G01X22298Y839573D02*
Y536902D01*
G01X20099Y534401D02*
Y840486D01*
G01X22589Y531911D02*
X20099Y534401D01*
G01X167419Y531911D02*
X22589D01*
G01X21677Y529711D02*
X59638D01*
G01X17899Y533489D02*
X21677Y529711D01*
G01X17899Y841398D02*
Y533489D01*
G01X12891Y534709D02*
Y839759D01*
G01X20089Y527511D02*
X12891Y534709D01*
G01X47607Y527511D02*
X20089D01*
G01X54852Y872127D02*
X22298Y839573D01*
G01X20099Y840486D02*
X52652Y873039D01*
G01X12891Y839759D02*
X48252Y875120D01*
G01X50452Y873951D02*
X17899Y841398D01*
G01X19712Y1035991D02*
X50452Y1005251D01*
G01X48252Y1004339D02*
X17512Y1035079D01*
G01X19712Y1176350D02*
Y1035991D01*
G01X17512Y1035079D02*
Y1209896D01*
G01X23700Y1119061D02*
X26723Y1116038D01*
G01X23700Y1176050D02*
Y1119061D01*
G01X34196Y1186546D02*
X23700Y1176050D01*
G01X17512Y1209896D02*
X31558Y1223942D01*
G01X24900Y534300D02*
X179261D01*
G01X59638Y529711D02*
X61834Y527515D01*
G01X27143Y677857D02*
Y663071D01*
G01X25200Y679800D02*
X27143Y677857D01*
G01X25200Y705968D02*
Y679800D01*
G01X27510Y704810D02*
Y688422D01*
G01X27600Y708368D02*
X25200Y705968D01*
G01X27600Y840500D02*
Y708368D01*
G01X29800Y707100D02*
X27510Y704810D01*
G01X29800Y839588D02*
Y707100D01*
G01X60952Y873852D02*
X27600Y840500D01*
G01X63152Y872940D02*
X29800Y839588D01*
G01X60952Y1004087D02*
Y873852D01*
G01X54852Y1007075D02*
Y872127D01*
G01X52652Y873039D02*
Y1006163D01*
G01X50452Y1005251D02*
Y873951D01*
G01X48252Y875120D02*
Y1004339D01*
G01X63152Y1004999D02*
Y872940D01*
G01X37255Y1027784D02*
X60952Y1004087D01*
G01X37255Y1136730D02*
Y1027784D01*
G01X35055Y1026872D02*
X54852Y1007075D01*
G01X35055Y1137642D02*
Y1026872D01*
G01X33355Y1025460D02*
Y1176690D01*
G01X52652Y1006163D02*
X33355Y1025460D01*
G01X39325Y1028826D02*
X63152Y1004999D01*
G01X39325Y1131400D02*
Y1028826D01*
G01X41625Y1141100D02*
X37255Y1136730D01*
G01X41625Y1332473D02*
Y1141100D01*
G01X35555Y1138142D02*
X35055Y1137642D01*
G01X35555Y1172307D02*
Y1138142D01*
G01X36848Y1173600D02*
X35555Y1172307D01*
G01X33355Y1176690D02*
X39425Y1182760D01*
G01X27090Y1174358D02*
X37225Y1184493D01*
G01X27090Y1141389D02*
Y1174358D01*
G01X34196Y1328382D02*
Y1186546D01*
G01X39425Y1182760D02*
Y1226200D01*
G01X37225Y1184493D02*
Y1230100D01*
G01X31558Y1223942D02*
X31500Y1224000D01*
G01X41381Y1335567D02*
X34196Y1328382D01*
G01X45518Y1336366D02*
X41625Y1332473D01*
G01X90200Y181898D02*
X95437Y176661D01*
G01X90200Y197100D02*
Y181898D01*
G01X91800Y198700D02*
X90200Y197100D01*
G01X91800Y236200D02*
Y198700D01*
G01X146600Y291000D02*
X91800Y236200D01*
G01X99600Y643100D02*
Y713299D01*
G01X85146Y628646D02*
X99600Y643100D01*
G01X85146Y621637D02*
Y628646D01*
G01X113637Y732837D02*
X197600Y816800D01*
G01X113637Y727336D02*
Y732837D01*
G01X99600Y713299D02*
X113637Y727336D01*
G01X106700Y1036800D02*
X229400D01*
G01X97700Y1045800D02*
X106700Y1036800D01*
G01X97700Y1080010D02*
Y1045800D01*
G01X95537Y1082173D02*
X97700Y1080010D01*
G01X253200Y291000D02*
X146600D01*
G01X145437Y286725D02*
Y265561D01*
G01X147511Y288799D02*
X145437Y286725D01*
G01X254111Y288799D02*
X147511D01*
G01X171861Y527469D02*
X167419Y531911D01*
G01X145437Y717617D02*
Y757837D01*
G01X150253Y709713D02*
Y758463D01*
G01X140364Y756452D02*
X199800Y815888D01*
G01X140364Y749807D02*
Y756452D01*
G01X145437Y757837D02*
X202000Y814400D01*
G01X150253Y758463D02*
X207500Y815710D01*
G01X145437Y1089863D02*
X148400Y1086900D01*
G01X145437Y1165673D02*
Y1089863D01*
G01X150862Y1152723D02*
Y1210862D01*
G01X148311Y1182767D02*
Y1228789D01*
G01X166000Y1226000D02*
Y1342700D01*
G01X150862Y1210862D02*
X166000Y1226000D01*
G01X148311Y1228789D02*
X148300Y1228800D01*
G01X166000Y1342700D02*
X163500Y1345200D01*
G01X214100Y182310D02*
X219749Y176661D01*
G01X214100Y196400D02*
Y182310D01*
G01X262597Y244897D02*
X214100Y196400D01*
G01X179261Y534300D02*
X186088Y527473D01*
G01X214000Y624666D02*
X219749Y618917D01*
G01X214000Y649006D02*
Y624666D01*
G01X217494Y652500D02*
X214000Y649006D01*
G01X199800Y815888D02*
Y916724D01*
G01X202000Y814400D02*
Y915812D01*
G01X197600Y816800D02*
Y920900D01*
G01X207500Y815710D02*
Y918200D01*
G01X199800Y916724D02*
X242099Y959023D01*
G01X223100Y920600D02*
X217494Y914994D01*
G01X202000Y915812D02*
X248099Y961911D01*
G01X197600Y920900D02*
X199900Y923200D01*
G01X207500Y918200D02*
X250699Y961399D01*
G01X226205Y1072605D02*
X208037Y1090773D01*
G01X195100Y1094100D02*
Y1096800D01*
G01X198427Y1090773D02*
X195100Y1094100D01*
G01X208037Y1090773D02*
X198427D01*
G01X262597Y518560D02*
Y244897D01*
G01X257597Y295397D02*
X253200Y291000D01*
G01X257597Y519784D02*
Y295397D01*
G01X259797Y294485D02*
X254111Y288799D01*
G01X259797Y518872D02*
Y294485D01*
G01X299653Y561840D02*
X257597Y519784D01*
G01X304053Y560016D02*
X262597Y518560D01*
G01X301853Y560928D02*
X259797Y518872D01*
G01X217494Y914994D02*
Y652500D01*
G01X258600Y715500D02*
Y754564D01*
G01X257699Y755465D02*
Y992923D01*
G01X258600Y754564D02*
X257699Y755465D01*
G01X259899Y756377D02*
Y992011D01*
G01X261800Y754476D02*
X259899Y756377D01*
G01X261800Y752482D02*
Y754476D01*
G01X264731Y749551D02*
X261800Y752482D01*
G01X262099Y757289D02*
Y991099D01*
G01X268450Y750938D02*
X262099Y757289D01*
G01X242099Y959023D02*
Y1033901D01*
G01X239500Y986100D02*
X239000Y985600D01*
G01X239500Y1026700D02*
Y986100D01*
G01X248099Y961911D02*
Y1001101D01*
G01X255500Y985500D02*
Y988364D01*
G01X250699Y980699D02*
X255500Y985500D01*
G01X250699Y961399D02*
Y980699D01*
G01X261100Y996324D02*
Y1005700D01*
G01X257699Y992923D02*
X261100Y996324D01*
G01X242099Y1033901D02*
X226205Y1049795D01*
G01X259899Y992011D02*
X267700Y999812D01*
G01X262099Y991099D02*
X269900Y998900D01*
G01X229400Y1036800D02*
X239500Y1026700D01*
G01X248099Y1001101D02*
X244600Y1004600D01*
G01X258500Y996836D02*
Y1076000D01*
G01X255499Y993835D02*
X258500Y996836D01*
G01X255499Y988365D02*
Y993835D01*
G01X255500Y988364D02*
X255499Y988365D01*
G01X252100Y990100D02*
Y1068200D01*
G01X226205Y1049795D02*
Y1072605D01*
G01X264864Y1059136D02*
Y1120500D01*
G01X267700Y1056300D02*
X264864Y1059136D01*
G01X258500Y1076000D02*
X249307Y1085193D01*
G01X228310Y1073612D02*
X219749Y1082173D01*
G01X246688Y1073612D02*
X228310D01*
G01X252100Y1068200D02*
X246688Y1073612D01*
G01X249307Y1085193D02*
Y1221442D01*
G01X262512Y1154434D02*
X272876Y1164798D01*
G01X262512Y1138612D02*
Y1154434D01*
G01X273364Y1127760D02*
X262512Y1138612D01*
G01X260312Y1156336D02*
X269649Y1165673D01*
G01X260312Y1137186D02*
Y1156336D01*
G01X271164Y1126334D02*
X260312Y1137186D01*
G01X249307Y1221442D02*
X279900Y1252035D01*
G01X291697Y212003D02*
X356838Y146862D01*
G01X291697Y418407D02*
Y212003D01*
G01X282997Y215705D02*
X347881Y150821D01*
G01X269500Y215100D02*
X335400Y149200D01*
G01X287497Y213504D02*
X350441Y150560D01*
G01X280397Y216006D02*
X346223Y150180D01*
G01X282997Y520233D02*
Y215705D01*
G01X269500Y215427D02*
Y215100D01*
G01X269262Y215665D02*
X269500Y215427D01*
G01X269262Y257100D02*
Y215665D01*
G01X271588Y259426D02*
X269262Y257100D01*
G01X271588Y267063D02*
Y259426D01*
G01X287497Y492903D02*
Y213504D01*
G01X280397Y519932D02*
Y216006D01*
G01X267597Y268313D02*
X269649Y266261D01*
G01X267597Y520448D02*
Y268313D01*
G01X269535Y269116D02*
X271588Y267063D01*
G01X269535Y519645D02*
Y269116D01*
G01X291601Y418503D02*
X291697Y418407D01*
G01X286340Y494060D02*
X287497Y492903D01*
G01X286340Y521277D02*
Y494060D01*
G01X296032Y527469D02*
X321701Y553138D01*
G01X306325Y559176D02*
X267597Y520448D01*
G01X317840Y555076D02*
X282997Y520233D01*
G01X308493Y558603D02*
X269535Y519645D01*
G01X319465Y554402D02*
X286340Y521277D01*
G01X310259Y536759D02*
X327401Y553901D01*
G01X310259Y527473D02*
Y536759D01*
G01X316215Y555750D02*
X280397Y519932D01*
G01X299653Y609565D02*
Y561840D01*
G01X304053Y611389D02*
Y560016D01*
G01X301853Y610477D02*
Y560928D01*
G01X306325Y612229D02*
Y559176D01*
G01X308493Y612802D02*
Y558603D01*
G01X278700Y630518D02*
X299653Y609565D01*
G01X278700Y703800D02*
Y630518D01*
G01X286536Y628906D02*
X304053Y611389D01*
G01X286536Y744164D02*
Y628906D01*
G01X281500Y630830D02*
X301853Y610477D01*
G01X281500Y703400D02*
Y630830D01*
G01X288736Y629818D02*
X306325Y612229D01*
G01X288736Y745590D02*
Y629818D01*
G01X305240Y636491D02*
X317840Y623891D01*
G01X305240Y712790D02*
Y636491D01*
G01X290867Y630428D02*
X308493Y612802D01*
G01X290867Y746200D02*
Y630428D01*
G01X310429Y634613D02*
X319465Y625577D01*
G01X310429Y709900D02*
Y634613D01*
G01X300778Y638654D02*
X316215Y623217D01*
G01X300778Y714953D02*
Y638654D01*
G01X308999Y715789D02*
Y1097911D01*
G01X316100Y708688D02*
X308999Y715789D01*
G01X281000Y706100D02*
X278700Y703800D01*
G01X281000Y722688D02*
Y706100D01*
G01X270650Y733038D02*
X281000Y722688D01*
G01X270650Y751850D02*
Y733038D01*
G01X273000Y757700D02*
X286536Y744164D01*
G01X283700Y705600D02*
X281500Y703400D01*
G01X283700Y723100D02*
Y705600D01*
G01X272850Y733950D02*
X283700Y723100D01*
G01X272850Y753350D02*
Y733950D01*
G01X268450Y715527D02*
Y750938D01*
G01X274520Y709457D02*
X268450Y715527D01*
G01X299968Y718062D02*
X305240Y712790D01*
G01X299968Y749973D02*
Y718062D01*
G01X301593Y718736D02*
X310429Y709900D01*
G01X301593Y750647D02*
Y718736D01*
G01X311200Y716700D02*
Y1097000D01*
G01X318300Y709600D02*
X311200Y716700D01*
G01X298343Y717388D02*
X300778Y714953D01*
G01X298343Y749299D02*
Y717388D01*
G01X268100Y754400D02*
X270650Y751850D01*
G01X268100Y982300D02*
Y754400D01*
G01X273000Y981400D02*
Y757700D01*
G01X270600Y755600D02*
X272850Y753350D01*
G01X270600Y996488D02*
Y755600D01*
G01X277400Y756926D02*
X288736Y745590D01*
G01X277400Y1029200D02*
Y756926D01*
G01X297575Y752366D02*
X299968Y749973D01*
G01X297575Y1080426D02*
Y752366D01*
G01X279362Y757705D02*
X290867Y746200D01*
G01X279362Y1009962D02*
Y757705D01*
G01X299200Y753040D02*
X301593Y750647D01*
G01X299200Y1081100D02*
Y753040D01*
G01X292650Y754992D02*
X298343Y749299D01*
G01X292650Y1204050D02*
Y754992D01*
G01X273300Y981700D02*
X273000Y981400D01*
G01X272100Y997988D02*
X270600Y996488D01*
G01X272100Y1027344D02*
Y997988D01*
G01X281500Y1036744D02*
X272100Y1027344D01*
G01X267700Y999812D02*
Y1056300D01*
G01X269900Y998900D02*
Y1039600D01*
G01X281200Y1033000D02*
X277400Y1029200D01*
G01X280800Y1011400D02*
X279362Y1009962D01*
G01X280800Y1011900D02*
Y1011400D01*
G01X273364Y1043064D02*
Y1127760D01*
G01X269900Y1039600D02*
X273364Y1043064D01*
G01X294275Y1083726D02*
X297575Y1080426D01*
G01X271164Y1063264D02*
Y1126334D01*
G01X271100Y1063200D02*
X271164Y1063264D01*
G01X295900Y1084400D02*
X299200Y1081100D01*
G01X308999Y1097911D02*
X315596Y1104508D01*
G01X294275Y1205100D02*
Y1083726D01*
G01X295900Y1327300D02*
Y1084400D01*
G01X311200Y1097000D02*
X318125Y1103925D01*
G01X280697Y1169191D02*
Y1201697D01*
G01X275385Y1163879D02*
X280697Y1169191D01*
G01X275385Y1152596D02*
Y1163879D01*
G01X272876Y1176924D02*
X270070Y1179730D01*
G01X272876Y1164798D02*
Y1176924D01*
G01X273243Y1226243D02*
X276100Y1229100D01*
G01X273243Y1182915D02*
Y1226243D01*
G01X285900Y1206900D02*
Y1349459D01*
G01X280697Y1201697D02*
X285900Y1206900D01*
G01X270070Y1179730D02*
Y1237170D01*
G01X293263Y1206112D02*
X294275Y1205100D01*
G01X293263Y1332263D02*
Y1206112D01*
G01X291638Y1205062D02*
X292650Y1204050D01*
G01X291638Y1336405D02*
Y1205062D01*
G01X283700Y1250800D02*
Y1328300D01*
G01X270070Y1237170D02*
X283700Y1250800D01*
G01X279900Y1252035D02*
Y1328300D01*
G01X285900Y1349459D02*
X286100Y1349659D01*
G01X296100Y1335100D02*
X293263Y1332263D01*
G01X298038Y1329438D02*
X295900Y1327300D01*
G01X298038Y1337562D02*
Y1329438D01*
G01X295900Y1339700D02*
X298038Y1337562D01*
G01X292600Y1337367D02*
X291638Y1336405D01*
G01X356838Y64838D02*
X354100Y62100D01*
G01X356838Y146862D02*
Y64838D01*
G01X347881Y150821D02*
Y114881D01*
G01X335400Y112321D02*
X345321Y102400D01*
G01X335400Y149200D02*
Y112321D01*
G01X350441Y150560D02*
Y117541D01*
G01X346223Y119823D02*
X345321Y118921D01*
G01X346223Y150180D02*
Y119823D01*
G01X346800Y179199D02*
X344062Y176461D01*
G01X346800Y307300D02*
Y179199D01*
G01X337500Y316600D02*
X346800Y307300D01*
G01X337500Y619000D02*
Y316600D01*
G01X339700Y332319D02*
X386800Y285219D01*
G01X339700Y618088D02*
Y332319D01*
G01X321701Y553138D02*
Y629380D01*
G01X317840Y623891D02*
Y555076D01*
G01X319465Y625577D02*
Y554402D01*
G01X327401Y553901D02*
Y626792D01*
G01X316215Y623217D02*
Y555750D01*
G01X316100Y634981D02*
Y708688D01*
G01X321701Y629380D02*
X316100Y634981D01*
G01X333682Y629670D02*
Y621858D01*
G01X343400Y639388D02*
X333682Y629670D01*
G01X343400Y736100D02*
Y639388D01*
G01X346800Y628300D02*
X337500Y619000D01*
G01X346800Y735812D02*
Y628300D01*
G01X350673Y629061D02*
X339700Y618088D01*
G01X350673Y736200D02*
Y629061D01*
G01X318300Y635893D02*
Y709600D01*
G01X327401Y626792D02*
X318300Y635893D01*
G01X337900Y741600D02*
X343400Y736100D01*
G01X337900Y924300D02*
Y741600D01*
G01X340100Y742512D02*
X346800Y735812D01*
G01X340100Y969100D02*
Y742512D01*
G01X346550Y740323D02*
X350673Y736200D01*
G01X346550Y755550D02*
Y740323D01*
G01X343000Y759100D02*
X346550Y755550D01*
G01X343000Y961800D02*
Y759100D01*
G01X335300Y926900D02*
X337900Y924300D01*
G01X337100Y972100D02*
X340100Y969100D01*
G01X350673Y969473D02*
X343000Y961800D01*
G01X350673Y1031200D02*
Y969473D01*
G01X341900Y998474D02*
X344737Y995637D01*
G01X341900Y1079911D02*
Y998474D01*
G01X344062Y1082073D02*
X341900Y1079911D01*
G01X315596Y1104508D02*
Y1216604D01*
G01X318125Y1103925D02*
Y1162246D01*
G01D02*
X331679Y1175800D01*
G01X315596Y1216604D02*
X315500Y1216700D01*
G01X421107Y148879D02*
X399727Y170259D01*
G01X423936Y149892D02*
X402465Y171363D01*
G01X417869Y147826D02*
X396727Y168968D01*
G01X407340Y173795D02*
Y327813D01*
G01X434417Y146718D02*
X407340Y173795D01*
G01X399727Y170259D02*
Y330970D01*
G01X402465Y171363D02*
Y329835D01*
G01X405715Y172711D02*
Y328487D01*
G01X432249Y146177D02*
X405715Y172711D01*
G01X396727Y168968D02*
Y332213D01*
G01X404090Y172037D02*
Y329161D01*
G01X426637Y149490D02*
X404090Y172037D01*
G01X386800Y285219D02*
Y263800D01*
G01X407340Y327813D02*
X426000Y346473D01*
G01X399727Y330970D02*
X412744Y343987D01*
G01X402465Y329835D02*
X418600Y345970D01*
G01X405715Y328487D02*
X424100Y346872D01*
G01X409544Y345030D02*
Y492478D01*
G01X396727Y332213D02*
X409544Y345030D01*
G01X404090Y329161D02*
X421700Y346771D01*
G01X412744Y493521D02*
X403783Y502482D01*
G01D02*
Y673898D01*
G01X424100Y487980D02*
X406521Y505559D01*
G01X409544Y492478D02*
X399488Y502534D01*
G01D02*
Y673846D01*
G01X408146Y514254D02*
Y672089D01*
G01X408015Y514123D02*
X408146Y514254D01*
G01X408015Y510465D02*
Y514123D01*
G01X408146Y510334D02*
X408015Y510465D01*
G01X408146Y506234D02*
Y510334D01*
G01X426000Y488380D02*
X408146Y506234D01*
G01X406521Y514928D02*
Y672763D01*
G01X406390Y514797D02*
X406521Y514928D01*
G01X406390Y509791D02*
Y514797D01*
G01X406521Y509660D02*
X406390Y509791D01*
G01X406521Y505559D02*
Y509660D01*
G01X408146Y672089D02*
X419346Y683289D01*
G01X403783Y673898D02*
X416096Y686211D01*
G01X406521Y672763D02*
X417721Y683963D01*
G01X399488Y673846D02*
X414471Y688829D01*
G01X398677Y725800D02*
Y709385D01*
G01X412846Y739969D02*
X398677Y725800D01*
G01X393862Y726900D02*
Y719917D01*
G01X411221Y744259D02*
X393862Y726900D01*
G01X409596Y770287D02*
Y897004D01*
G01X388788Y749479D02*
X409596Y770287D01*
G01X402150Y904450D02*
Y1053738D01*
G01X409596Y897004D02*
X402150Y904450D01*
G01X408672Y901040D02*
X411221Y898491D01*
G01X408672Y1008038D02*
Y901040D01*
G01X400442Y1077292D02*
Y1151399D01*
G01X416981Y1060753D02*
X400442Y1077292D01*
G01X391100Y1069300D02*
X412846Y1047554D01*
G01X391100Y1123256D02*
Y1069300D01*
G01X388888Y1067000D02*
Y1118173D01*
G01X402150Y1053738D02*
X388888Y1067000D01*
G01X393679Y1073521D02*
X413000Y1054200D01*
G01X393679Y1157480D02*
Y1073521D01*
G01X397442Y1078535D02*
Y1152642D01*
G01X397441Y1078534D02*
X397442Y1078535D01*
G01X397441Y1076050D02*
Y1078534D01*
G01X415356Y1058135D02*
X397441Y1076050D01*
G01X379540Y1134816D02*
X391100Y1123256D01*
G01X400442Y1151399D02*
X413870Y1164827D01*
G01X379540Y1179556D02*
Y1134816D01*
G01X386049Y1186065D02*
X379540Y1179556D01*
G01X388416Y1175428D02*
Y1183751D01*
G01X383191Y1170203D02*
X388416Y1175428D01*
G01X397442Y1152642D02*
X410870Y1166070D01*
G01X386049Y1232449D02*
Y1186065D01*
G01X396135Y1191470D02*
Y1239423D01*
G01X388416Y1183751D02*
X396135Y1191470D01*
G01X398527Y1188659D02*
Y1233336D01*
G01X412300Y1258700D02*
X386049Y1232449D01*
G01X396135Y1239423D02*
X415422Y1258710D01*
G01X410870Y1244534D02*
X418922Y1252586D01*
G01X455525Y107992D02*
Y129578D01*
G01X454933Y107400D02*
X455525Y107992D01*
G01X454933Y105304D02*
Y107400D01*
G01X458071Y102166D02*
X454933Y105304D01*
G01X421107Y110783D02*
Y148879D01*
G01X429724Y102166D02*
X421107Y110783D01*
G01X446468Y99772D02*
Y123869D01*
G01X443898Y97202D02*
X446468Y99772D01*
G01X443898Y96654D02*
Y97202D01*
G01X429724Y110827D02*
X423936Y116615D01*
G01X436811Y114764D02*
X432249Y119326D01*
G01X417869Y108509D02*
Y147826D01*
G01X429724Y96654D02*
X417869Y108509D01*
G01X453650Y108769D02*
Y146703D01*
G01X450984Y106103D02*
X453650Y108769D01*
G01X434417Y122670D02*
Y146718D01*
G01X436811Y120276D02*
X434417Y122670D01*
G01X455494Y147189D02*
X425178Y177505D01*
G01X455494Y129609D02*
Y147189D01*
G01X455525Y129578D02*
X455494Y129609D01*
G01X444703Y148352D02*
X414900Y178155D01*
G01X444703Y125634D02*
Y148352D01*
G01X446468Y123869D02*
X444703Y125634D01*
G01X423936Y116615D02*
Y149892D01*
G01X432249Y119326D02*
Y146177D01*
G01X453650Y146703D02*
X420404Y179949D01*
G01X426637Y119426D02*
Y149490D01*
G01X429724Y116339D02*
X426637Y119426D01*
G01X425178Y177505D02*
Y218816D01*
G01X414900Y178155D02*
Y324870D01*
G01X444347Y181653D02*
Y230193D01*
G01X473808Y152192D02*
X444347Y181653D01*
G01X420404Y179949D02*
Y253816D01*
G01X425178Y220506D02*
Y323093D01*
G01X425136Y220464D02*
X425178Y220506D01*
G01X425136Y218858D02*
Y220464D01*
G01X425178Y218816D02*
X425136Y218858D01*
G01X444347Y251629D02*
Y310947D01*
G01X448012Y247964D02*
X444347Y251629D01*
G01X448012Y233858D02*
Y247964D01*
G01X444347Y230193D02*
X448012Y233858D01*
G01X420404Y255506D02*
Y322326D01*
G01X420362Y255464D02*
X420404Y255506D01*
G01X420362Y253858D02*
Y255464D01*
G01X420404Y253816D02*
X420362Y253858D01*
G01X426000Y346473D02*
Y488380D01*
G01X425178Y323093D02*
X456190Y354105D01*
G01X412744Y343987D02*
Y493521D01*
G01X414900Y324870D02*
X447533Y357503D01*
G01D02*
Y475900D01*
G01X418600Y345970D02*
Y445462D01*
G01X444347Y310947D02*
X481533Y348133D01*
G01X424100Y346872D02*
Y487980D01*
G01X452800Y354722D02*
Y420912D01*
G01X420404Y322326D02*
X452800Y354722D01*
G01X421700Y346771D02*
Y450200D01*
G01X420182Y527432D02*
Y655494D01*
G01X422331Y539514D02*
Y654531D01*
G01X434409Y527436D02*
X422331Y539514D01*
G01X457853Y631536D02*
Y622091D01*
G01X473200Y646883D02*
X457853Y631536D01*
G01X419346Y683289D02*
Y1001791D01*
G01X416096Y686211D02*
Y1045293D01*
G01X417721Y683963D02*
Y1006028D01*
G01X414471Y688829D02*
Y1045967D01*
G01X440371Y675683D02*
Y701683D01*
G01X420182Y655494D02*
X440371Y675683D01*
G01X442571Y674771D02*
Y700771D01*
G01X422331Y654531D02*
X442571Y674771D01*
G01X412846Y1047554D02*
Y739969D01*
G01X411221Y898491D02*
Y744259D01*
G01X430626Y725763D02*
X473200Y683189D01*
G01X430626Y896040D02*
Y725763D01*
G01X426771Y715283D02*
Y898829D01*
G01X440371Y701683D02*
X426771Y715283D01*
G01X428396Y715957D02*
Y896109D01*
G01X441996Y702357D02*
X428396Y715957D01*
G01X441996Y701346D02*
Y702357D01*
G01X442571Y700771D02*
X441996Y701346D01*
G01X433421Y727127D02*
Y896536D01*
G01X476605Y683943D02*
X433421Y727127D01*
G01X501226Y749732D02*
X438475Y812483D01*
G01X508300Y740359D02*
X436850Y811809D01*
G01X438475Y812483D02*
Y895472D01*
G01X436850Y811809D02*
Y896249D01*
G01X455050Y912047D02*
Y995289D01*
G01X438475Y895472D02*
X455050Y912047D01*
G01X452853Y912252D02*
Y1005853D01*
G01X436850Y896249D02*
X452853Y912252D01*
G01X444625Y910039D02*
X430626Y896040D01*
G01X444625Y924395D02*
Y910039D01*
G01X445582Y925352D02*
X444625Y924395D01*
G01X437750Y925250D02*
Y1126601D01*
G01X440800Y922200D02*
X437750Y925250D01*
G01X440800Y912858D02*
Y922200D01*
G01X426771Y898829D02*
X440800Y912858D01*
G01X443000Y910713D02*
Y964100D01*
G01X428396Y896109D02*
X443000Y910713D01*
G01X448952Y912067D02*
Y967572D01*
G01X433421Y896536D02*
X448952Y912067D01*
G01X439950Y967150D02*
Y1102438D01*
G01X443000Y964100D02*
X439950Y967150D01*
G01X448952Y967572D02*
X449137Y967757D01*
G01X419346Y1001791D02*
X432657Y1015102D01*
G01X455050Y995289D02*
X509037Y1049276D01*
G01X417721Y1006028D02*
X429613Y1017920D01*
G01X452853Y1005853D02*
X465200Y1018200D01*
G01X442473Y998427D02*
X442600Y998300D01*
G01X442473Y1068726D02*
Y998427D01*
G01X416981Y1046178D02*
Y1060753D01*
G01X416096Y1045293D02*
X416981Y1046178D01*
G01X415356Y1046852D02*
Y1058135D01*
G01X414471Y1045967D02*
X415356Y1046852D01*
G01X437750Y1126601D02*
X443000Y1131851D01*
G01X444176Y1129915D02*
X446200Y1131939D01*
G01X444176Y1106664D02*
Y1129915D01*
G01X439950Y1102438D02*
X444176Y1106664D01*
G01X413870Y1164827D02*
Y1243291D01*
G01X410870Y1166070D02*
Y1244534D01*
G01X443000Y1160700D02*
X416870Y1186830D01*
G01X443000Y1131851D02*
Y1160700D01*
G01X446200Y1164600D02*
X441400Y1169400D01*
G01X446200Y1131939D02*
Y1164600D01*
G01X416870Y1221770D02*
X416900Y1221800D01*
G01X416870Y1186830D02*
Y1221770D01*
G01X422373Y1251794D02*
Y1359747D01*
G01X413870Y1243291D02*
X422373Y1251794D01*
G01X412300Y1326200D02*
Y1258700D01*
G01X415422Y1258710D02*
Y1352000D01*
G01X418922Y1252586D02*
Y1356522D01*
G01X476100Y109334D02*
Y138362D01*
G01X479331Y106103D02*
X476100Y109334D01*
G01X473808Y140654D02*
Y152192D01*
G01X476100Y138362D02*
X473808Y140654D01*
G01X464773Y175682D02*
Y328632D01*
G01X462200Y173109D02*
X464773Y175682D01*
G01X481533Y348133D02*
Y480875D01*
G01X491149Y351400D02*
Y485337D01*
G01X491150Y351399D02*
X491149Y351400D01*
G01X491150Y349252D02*
Y351399D01*
G01X510700Y329702D02*
X491150Y349252D01*
G01X483733Y347592D02*
Y484267D01*
G01X464773Y328632D02*
X483733Y347592D01*
G01X475022Y501464D02*
Y628239D01*
G01X491149Y485337D02*
X475022Y501464D01*
G01X467647Y500353D02*
Y628610D01*
G01X483733Y484267D02*
X467647Y500353D01*
G01X489018Y642235D02*
Y649504D01*
G01X475022Y628239D02*
X489018Y642235D01*
G01X473200Y683189D02*
Y646883D01*
G01X476605Y637568D02*
Y683943D01*
G01X467647Y628610D02*
X476605Y637568D01*
G01X489018Y649504D02*
X513001Y673487D01*
G01X512884Y749732D02*
X501226D01*
G01X506500Y1051900D02*
Y1100700D01*
G01X502300Y1104900D02*
Y1131199D01*
G01X506500Y1100700D02*
X502300Y1104900D01*
G01Y1131199D02*
X505874Y1134773D01*
G01X553742Y511053D02*
Y267705D01*
G01X510700Y277200D02*
Y329702D01*
G01X534905Y485473D02*
Y354105D01*
G01X536288Y486856D02*
X534905Y485473D01*
G01X536288Y488462D02*
Y486856D01*
G01X534905Y489845D02*
X536288Y488462D01*
G01X534905Y502095D02*
Y489845D01*
G01X530400Y506600D02*
X534905Y502095D01*
G01X555217Y512528D02*
X553742Y511053D01*
G01X555217Y514134D02*
Y512528D01*
G01X553742Y515609D02*
X555217Y514134D01*
G01X553742Y522868D02*
Y515609D01*
G01X553279Y523331D02*
X553742Y522868D01*
G01X530400Y516000D02*
Y506600D01*
G01X520734Y525666D02*
X530400Y516000D01*
G01X520734Y546666D02*
Y525666D01*
G01X518700Y548700D02*
X520734Y546666D01*
G01X514500Y568674D02*
Y524469D01*
G01X522713Y530987D02*
Y563437D01*
G01X528727Y524973D02*
X522713Y530987D01*
G01X509211Y573963D02*
X514500Y568674D01*
G01X509211Y618570D02*
Y573963D01*
G01X510836Y575314D02*
Y617896D01*
G01X522713Y563437D02*
X510836Y575314D01*
G01X541887Y651246D02*
X509211Y618570D01*
G01X510836Y617896D02*
X544087Y651147D01*
G01X513001Y673487D02*
Y711601D01*
G01X541887Y678509D02*
Y651246D01*
G01X590349Y726971D02*
X541887Y678509D01*
G01X544087Y677116D02*
X597465Y730494D01*
G01X544087Y651147D02*
Y677116D01*
G01X518289Y723196D02*
X562912Y767819D01*
G01X518289Y716889D02*
Y723196D01*
G01X513001Y711601D02*
X518289Y716889D01*
G01X522773Y725381D02*
X566931Y769539D01*
G01X522773Y709638D02*
Y725381D01*
G01X508300Y718692D02*
Y740359D01*
G01X509996Y716996D02*
X508300Y718692D01*
G01X530799Y931403D02*
Y952511D01*
G01X562912Y899290D02*
X530799Y931403D01*
G01X532999Y933979D02*
Y1121844D01*
G01X566931Y900047D02*
X532999Y933979D01*
G01X530800Y952512D02*
Y1028300D01*
G01X530799Y952511D02*
X530800Y952512D01*
G01X509037Y1049276D02*
Y1136700D01*
G01X529680Y1125163D02*
Y1158666D01*
G01X532999Y1121844D02*
X529680Y1125163D01*
G01X532200Y1161186D02*
Y1233700D01*
G01X529680Y1158666D02*
X532200Y1161186D01*
G01X529015Y1163418D02*
Y1233773D01*
G01X524828Y1159231D02*
X529015Y1163418D01*
G01X522867Y1231097D02*
Y1190284D01*
G01X520600Y1245300D02*
Y1324100D01*
G01X532200Y1233700D02*
X520600Y1245300D01*
G01X518399Y1244389D02*
Y1359998D01*
G01X529015Y1233773D02*
X518399Y1244389D01*
G01Y1359998D02*
X518397Y1360000D01*
G01X594200Y180710D02*
Y276862D01*
G01X592767Y179277D02*
X594200Y180710D01*
G01X566271Y204827D02*
Y167387D01*
G01X576844Y215400D02*
X566271Y204827D01*
G01X576844Y400703D02*
Y215400D01*
G01X594200Y276862D02*
X667874Y350536D01*
G01X599711Y423570D02*
X576844Y400703D01*
G01X599711Y490011D02*
Y423570D01*
G01X612000Y502300D02*
X599711Y490011D01*
G01X591500Y645600D02*
Y661700D01*
G01X589800Y643900D02*
X591500Y645600D01*
G01X589800Y632004D02*
Y643900D01*
G01X592387Y629417D02*
X589800Y632004D01*
G01X591500Y661700D02*
X634400Y704600D01*
G01X590349Y753720D02*
Y726971D01*
G01X597465Y730494D02*
Y1077072D01*
G01X562912Y767819D02*
Y899290D01*
G01X566931Y769539D02*
Y900047D01*
G01X595840Y759211D02*
X590349Y753720D01*
G01X595840Y1077690D02*
Y759211D01*
G01X571300Y1000200D02*
X571400Y1000100D01*
G01X571300Y1061086D02*
Y1000200D01*
G01X592387Y1082173D02*
X571300Y1061086D01*
G01X595812Y1077718D02*
X595840Y1077690D01*
G01X595500Y1078031D02*
X595812Y1077718D01*
G01X595500Y1078700D02*
Y1078031D01*
G01X598024Y1081224D02*
X595500Y1078700D01*
G01X598024Y1208832D02*
Y1081224D01*
G01X600640Y1080247D02*
Y1171000D01*
G01X597465Y1077072D02*
X600640Y1080247D01*
G01X592400Y1214456D02*
X598024Y1208832D01*
G01X642287Y319855D02*
Y266461D01*
G01X670074Y347642D02*
X642287Y319855D01*
G01X642509Y520667D02*
X695566D01*
G01X629963Y524100D02*
X627863Y522000D01*
G01X695887Y524100D02*
X629963D01*
G01X639518Y742018D02*
Y770363D01*
G01X634400Y736900D02*
X639518Y742018D01*
G01X634400Y704600D02*
Y736900D01*
G01X642287Y719817D02*
Y770020D01*
G01X647207Y709555D02*
Y771828D01*
G01X637318Y771275D02*
X657600Y791557D01*
G01X637318Y749649D02*
Y771275D01*
G01X639518Y770363D02*
X659800Y790645D01*
G01X642287Y770020D02*
X662000Y789733D01*
G01X647207Y771828D02*
X664200Y788821D01*
G01X650800Y931650D02*
Y1015400D01*
G01X657600Y924850D02*
X650800Y931650D01*
G01X632603Y1033597D02*
Y1136225D01*
G01X650800Y1015400D02*
X632603Y1033597D01*
G01X639900Y1057424D02*
Y1147378D01*
G01X671800Y1025524D02*
X639900Y1057424D01*
G01X645200Y1067800D02*
Y1154560D01*
G01X637700Y1056512D02*
X669600Y1024612D01*
G01X637700Y1145705D02*
Y1056512D01*
G01X634803Y1056297D02*
Y1145490D01*
G01X667400Y1023700D02*
X634803Y1056297D01*
G01X636806Y1167861D02*
X636803Y1167864D01*
G01X636806Y1150472D02*
Y1167861D01*
G01X639900Y1147378D02*
X636806Y1150472D01*
G01X642500Y1175500D02*
Y1206500D01*
G01X647716Y1170284D02*
X642500Y1175500D01*
G01X647716Y1154150D02*
Y1170284D01*
G01X645200Y1154560D02*
X642942Y1156818D01*
G01X625874Y1157531D02*
X637700Y1145705D01*
G01X625874Y1215542D02*
Y1157531D01*
G01X623661Y1156632D02*
Y1218062D01*
G01X634803Y1145490D02*
X623661Y1156632D01*
G01X647126Y1189513D02*
X717674Y1260061D01*
G01X642500Y1206500D02*
X673000Y1237000D01*
G01X627632Y1217300D02*
X625874Y1215542D01*
G01X623661Y1218062D02*
X664000Y1258401D01*
G01X667874Y350536D02*
Y489863D01*
G01X670074Y488951D02*
Y347642D01*
G01X667874Y489863D02*
X713000Y534989D01*
G01X715200Y534077D02*
X670074Y488951D01*
G01X695566Y520667D02*
X710800Y535901D01*
G01X708600Y536813D02*
X695887Y524100D01*
G01X683500Y639791D02*
Y657500D01*
G01X690394Y632897D02*
X683500Y639791D01*
G01X705310Y632897D02*
X690394D01*
G01X689500Y640522D02*
Y671000D01*
G01X695500Y634522D02*
X689500Y640522D01*
G01X705984Y634522D02*
X695500D01*
G01X689720Y631272D02*
X704636D01*
G01X681500Y639492D02*
X689720Y631272D01*
G01X681500Y656500D02*
Y639492D01*
G01X696500Y636147D02*
X706658D01*
G01X691500Y641147D02*
X696500Y636147D01*
G01X691500Y672000D02*
Y641147D01*
G01X661500Y679500D02*
Y778288D01*
G01X683500Y657500D02*
X661500Y679500D01*
G01X665700Y694800D02*
Y773800D01*
G01X689500Y671000D02*
X665700Y694800D01*
G01X659300Y678700D02*
X681500Y656500D01*
G01X659300Y777376D02*
Y678700D01*
G01X682200Y681300D02*
X691500Y672000D01*
G01X682200Y1026500D02*
Y681300D01*
G01X671800Y788588D02*
Y1025524D01*
G01X661500Y778288D02*
X671800Y788588D01*
G01X657600Y791557D02*
Y924850D01*
G01X677400Y785500D02*
Y944739D01*
G01X665700Y773800D02*
X677400Y785500D01*
G01X659299Y777377D02*
X659300Y777376D01*
G01X659299Y779199D02*
Y777377D01*
G01X669600Y789500D02*
X659299Y779199D01*
G01X669600Y1024612D02*
Y789500D01*
G01X659800Y790645D02*
Y928874D01*
G01X662000Y789733D02*
Y1016500D01*
G01X664200Y788821D02*
Y918800D01*
G01X659800Y928874D02*
X658574Y930100D01*
G01X667400Y922000D02*
Y1023700D01*
G01X664200Y918800D02*
X667400Y922000D01*
G01X677400Y944739D02*
X677457Y944796D01*
G01X674300Y1022485D02*
Y1001620D01*
G01X716600Y1064785D02*
X674300Y1022485D01*
G01X662000Y1016500D02*
X663800Y1018300D01*
G01X673000Y1237000D02*
Y1354100D01*
G01X664000Y1258401D02*
Y1278100D01*
G01X714200Y188596D02*
X740911Y215307D01*
G01X714200Y179449D02*
Y188596D01*
G01X717188Y176461D02*
X714200Y179449D01*
G01X750556Y197553D02*
X747242D01*
G01X740911Y215307D02*
Y593296D01*
G01X710800Y535901D02*
Y627407D01*
G01X713000Y534989D02*
Y627506D01*
G01X708600Y627308D02*
Y536813D01*
G01X715200Y627605D02*
Y534077D01*
G01X740911Y595956D02*
Y738212D01*
G01X741438Y595429D02*
X740911Y595956D01*
G01X741438Y593823D02*
Y595429D01*
G01X740911Y593296D02*
X741438Y593823D01*
G01X710800Y627407D02*
X705310Y632897D01*
G01X713000Y627506D02*
X705984Y634522D01*
G01X704636Y631272D02*
X708600Y627308D01*
G01X706658Y636147D02*
X715200Y627605D01*
G01X715700Y642012D02*
Y715300D01*
G01X720952Y636760D02*
X715700Y642012D01*
G01X720952Y633769D02*
Y636760D01*
G01X716600Y629417D02*
X720952Y633769D01*
G01X742225Y739526D02*
Y756225D01*
G01X740911Y738212D02*
X742225Y739526D01*
G01X740600Y740200D02*
Y757712D01*
G01X715700Y715300D02*
X740600Y740200D01*
G01X742225Y756225D02*
X780800Y794800D01*
G01X740600Y757712D02*
X776400Y793512D01*
G01X716600Y1081973D02*
Y1064785D01*
G01X717674Y1260061D02*
Y1293834D01*
G01X725765Y1272886D02*
Y1292586D01*
G01X725678Y1272799D02*
X725765Y1272886D01*
G01X728174Y1275611D02*
Y1291882D01*
G01X722790Y1270557D02*
Y1292724D01*
G01X720446Y1267427D02*
Y1293493D01*
G01X717674Y1293834D02*
X774790Y1350950D01*
G01X725765Y1292586D02*
X777528Y1344349D01*
G01X728174Y1291882D02*
X778441Y1342149D01*
G01X731500Y1292095D02*
X779354Y1339949D01*
G01X731500Y1277811D02*
Y1292095D01*
G01X722790Y1292724D02*
X776615Y1346549D01*
G01X720446Y1293493D02*
X775702Y1348749D01*
G01X757020Y159692D02*
X753006Y163706D01*
G01D02*
Y195103D01*
G01X773789Y211819D02*
X761119Y224489D01*
G01X773789Y179137D02*
Y211819D01*
G01X767152Y172500D02*
X773789Y179137D01*
G01X763188Y172500D02*
X767152D01*
G01X755813Y171343D02*
X758619Y168537D01*
G01X755813Y661987D02*
Y171343D01*
G01X753006Y195103D02*
X750556Y197553D01*
G01X761119Y224489D02*
Y336873D01*
G01D02*
X789739Y365493D01*
G01X758500Y672741D02*
Y765800D01*
G01X754500Y668741D02*
X758500Y672741D01*
G01X749550Y668250D02*
X755813Y661987D01*
G01X749550Y760250D02*
Y668250D01*
G01X758500Y765800D02*
X786800Y794100D01*
G01X784000Y794700D02*
X749550Y760250D01*
G01X780800Y794800D02*
Y959300D01*
G01X786800Y794100D02*
Y1016000D01*
G01X776400Y793512D02*
Y956500D01*
G01X784000Y1024000D02*
Y794700D01*
G01X752500Y1063100D02*
X759500Y1056100D01*
G01X752500Y1167500D02*
Y1063100D01*
G01X794524Y1130207D02*
X821442Y1103289D01*
G01X794524Y1186884D02*
Y1130207D01*
G01X774422Y1117826D02*
X799442Y1092806D01*
G01X774422Y1118639D02*
Y1117826D01*
G01X774021Y1119040D02*
X774422Y1118639D01*
G01X774021Y1119853D02*
Y1119040D01*
G01X774008Y1119866D02*
X774021Y1119853D01*
G01X774008Y1187942D02*
Y1119866D01*
G01X784544Y1123264D02*
X810442Y1097366D01*
G01X784544Y1205978D02*
Y1123264D01*
G01X782606Y1122090D02*
Y1208240D01*
G01X808242Y1096454D02*
X782606Y1122090D01*
G01X775633Y1120540D02*
Y1185367D01*
G01X775646Y1120527D02*
X775633Y1120540D01*
G01X775646Y1119714D02*
Y1120527D01*
G01X801642Y1093718D02*
X775646Y1119714D01*
G01X790217Y1128290D02*
X817042Y1101465D01*
G01X790217Y1172415D02*
Y1128290D01*
G01X786935Y1125348D02*
Y1177533D01*
G01X812642Y1099641D02*
X786935Y1125348D01*
G01X779535Y1122049D02*
Y1180469D01*
G01X806042Y1095542D02*
X779535Y1122049D01*
G01X797225Y1185337D02*
Y1130618D01*
G01D02*
X823642Y1104201D01*
G01X792263Y1129356D02*
X819242Y1102377D01*
G01X792263Y1170261D02*
Y1129356D01*
G01X788592Y1127616D02*
Y1174990D01*
G01X789049Y1127159D02*
X788592Y1127616D01*
G01X789049Y1126346D02*
Y1127159D01*
G01X814842Y1100553D02*
X789049Y1126346D01*
G01X777258Y1121214D02*
Y1182392D01*
G01X803842Y1094630D02*
X777258Y1121214D01*
G01X792263Y1174461D02*
X790217Y1172415D01*
G01X786935Y1177533D02*
X792263Y1182861D01*
G01X788592Y1174990D02*
X792263Y1178661D01*
G01X797177Y1189537D02*
X794524Y1186884D01*
G01X779535Y1193469D02*
X774008Y1187942D01*
G01X782606Y1208240D02*
X784544Y1210178D01*
G01X775633Y1185367D02*
X779535Y1189269D01*
G01X777258Y1182392D02*
X779535Y1184669D01*
G01X795818Y1369218D02*
Y1468694D01*
G01X777550Y1350950D02*
X795818Y1369218D01*
G01X774790Y1350950D02*
X777550D01*
G01X780285Y1344349D02*
X802418Y1366482D01*
G01X777528Y1344349D02*
X780285D01*
G01X781197Y1342149D02*
X804618Y1365570D01*
G01X778441Y1342149D02*
X781197D01*
G01X782109Y1339949D02*
X806800Y1364640D01*
G01X779354Y1339949D02*
X782109D01*
G01X779373Y1346549D02*
X800218Y1367394D01*
G01X776615Y1346549D02*
X779373D01*
G01X778461Y1348749D02*
X798018Y1368306D01*
G01X775702Y1348749D02*
X778461D01*
G01X795818Y1468694D02*
X796848Y1469724D01*
G01X833714Y-3346D02*
X833724D01*
G01X835775Y-1285D02*
X833714Y-3346D01*
G01X835775Y30181D02*
Y-1285D01*
G01X841104Y-4D02*
Y36025D01*
G01X842705Y-1605D02*
X841104Y-4D01*
G01X863142Y-1605D02*
X842705D01*
G01X829921Y-458D02*
Y31188D01*
G01X811533Y4776D02*
Y44486D01*
G01X806299Y-458D02*
X811533Y4776D01*
G01X838251Y435D02*
Y31036D01*
G01X842328Y-3642D02*
X838251Y435D01*
G01X845661Y-3642D02*
X842328D01*
G01X822150Y-355D02*
Y213848D01*
G01X822047Y-458D02*
X822150Y-355D01*
G01X847340Y4407D02*
X843463Y530D01*
G01X814173Y-458D02*
Y32146D01*
G01X836635Y54882D02*
X849432Y42085D01*
G01X836635Y192838D02*
Y54882D01*
G01X806299Y35967D02*
X806314Y35952D01*
G01X806299Y42389D02*
Y35967D01*
G01X816218Y52308D02*
X806299Y42389D01*
G01X816218Y216306D02*
Y52308D01*
G01X825699Y40257D02*
X835775Y30181D01*
G01X825699Y209604D02*
Y40257D01*
G01X841104Y36025D02*
X841733Y36654D01*
G01X824067Y37042D02*
Y211908D01*
G01X829921Y31188D02*
X824067Y37042D01*
G01X818073Y51026D02*
Y215537D01*
G01X811533Y44486D02*
X818073Y51026D01*
G01X833096Y53766D02*
X846182Y40680D01*
G01X833096Y193897D02*
Y53766D01*
G01X829432Y39855D02*
Y194831D01*
G01X838251Y31036D02*
X829432Y39855D01*
G01X838383Y55697D02*
X851057Y43023D01*
G01X838383Y192287D02*
Y55697D01*
G01X834944Y54267D02*
X847807Y41404D01*
G01X834944Y193446D02*
Y54267D01*
G01X831057Y52708D02*
Y194157D01*
G01X842470Y41295D02*
X831057Y52708D01*
G01X820238Y38211D02*
Y214640D01*
G01X814173Y32146D02*
X820238Y38211D01*
G01X868796Y224999D02*
X836635Y192838D01*
G01X847068Y230973D02*
X825699Y209604D01*
G01X824067Y211908D02*
X844285Y232126D01*
G01X865546Y226347D02*
X833096Y193897D01*
G01X829432Y194831D02*
X862296Y227695D01*
G01X870421Y224325D02*
X838383Y192287D01*
G01X867171Y225673D02*
X834944Y193446D01*
G01X831057Y194157D02*
X863921Y227021D01*
G01X835626Y235714D02*
X816218Y216306D01*
G01X835626Y282623D02*
Y235714D01*
G01X844285Y232126D02*
Y280045D01*
G01X837251Y239606D02*
Y284110D01*
G01X837481Y239376D02*
X837251Y239606D01*
G01X837481Y234945D02*
Y239376D01*
G01X818073Y215537D02*
X837481Y234945D01*
G01X841558Y233256D02*
Y286027D01*
G01X822150Y213848D02*
X841558Y233256D01*
G01X839646Y234048D02*
Y284827D01*
G01X820238Y214640D02*
X839646Y234048D01*
G01X818860Y299389D02*
X835626Y282623D01*
G01X818860Y572514D02*
Y299389D01*
G01X830568Y303241D02*
X847068Y286741D01*
G01X830568Y568662D02*
Y303241D01*
G01X828368Y302329D02*
Y569574D01*
G01X844327Y286370D02*
X828368Y302329D01*
G01X844327Y280087D02*
Y286370D01*
G01X844285Y280045D02*
X844327Y280087D01*
G01X821768Y299593D02*
Y572310D01*
G01X837251Y284110D02*
X821768Y299593D01*
G01X835443Y311562D02*
X853846Y293159D01*
G01X832193Y307226D02*
Y567175D01*
G01X850596Y288823D02*
X832193Y307226D01*
G01X826168Y301417D02*
Y570486D01*
G01X841558Y286027D02*
X826168Y301417D01*
G01X837068Y315572D02*
X855545Y297095D01*
G01X852221Y291672D02*
X833818Y310075D01*
G01X823968Y300505D02*
Y571398D01*
G01X839646Y284827D02*
X823968Y300505D01*
G01X838693Y319426D02*
X858158Y299961D01*
G01X838693Y479777D02*
Y319426D01*
G01X835443Y481125D02*
Y311562D01*
G01X840402Y322017D02*
X860208Y302211D01*
G01X840402Y478532D02*
Y322017D01*
G01X837068Y480451D02*
Y315572D01*
G01X833818Y310075D02*
Y565688D01*
G01X847338Y488422D02*
X838693Y479777D01*
G01X844088Y489770D02*
X835443Y481125D01*
G01X844088Y571985D02*
Y489770D01*
G01X848963Y487093D02*
X840402Y478532D01*
G01X845713Y489096D02*
X837068Y480451D01*
G01X845713Y570498D02*
Y489096D01*
G01X831067Y584721D02*
X818860Y572514D01*
G01X831067Y761889D02*
Y584721D01*
G01X842067Y580161D02*
X830568Y568662D01*
G01X842067Y766449D02*
Y580161D01*
G01X839867Y581073D02*
Y765537D01*
G01X828368Y569574D02*
X839867Y581073D01*
G01X833267Y583809D02*
Y762801D01*
G01X821768Y572310D02*
X833267Y583809D01*
G01X848667Y576564D02*
X844088Y571985D01*
G01X844267Y579249D02*
Y767361D01*
G01X832193Y567175D02*
X844267Y579249D01*
G01X837667Y581985D02*
Y764625D01*
G01X826168Y570486D02*
X837667Y581985D01*
G01X850867Y575652D02*
X845713Y570498D01*
G01X833818Y565688D02*
X846467Y578337D01*
G01X835467Y582897D02*
Y763713D01*
G01X823968Y571398D02*
X835467Y582897D01*
G01X821442Y802634D02*
X853067Y771009D01*
G01X799442Y793514D02*
X831067Y761889D01*
G01X810442Y798074D02*
X842067Y766449D01*
G01X839867Y765537D02*
X808242Y797162D01*
G01X833267Y762801D02*
X801642Y794426D01*
G01X817042Y800810D02*
X848667Y769185D01*
G01X844267Y767361D02*
X812642Y798986D01*
G01X837667Y764625D02*
X806042Y796250D01*
G01X823642Y803546D02*
X855267Y771921D01*
G01X819242Y801722D02*
X850867Y770097D01*
G01X846467Y768273D02*
X814842Y799898D01*
G01X835467Y763713D02*
X803842Y795338D01*
G01X821442Y1103289D02*
Y802634D01*
G01X799442Y1092806D02*
Y793514D01*
G01X810442Y1097366D02*
Y798074D01*
G01X808242Y797162D02*
Y1096454D01*
G01X840113Y810830D02*
Y1241856D01*
G01X911081Y739862D02*
X840113Y810830D01*
G01X801642Y794426D02*
Y1093718D01*
G01X817042Y1101465D02*
Y800810D01*
G01X812642Y798986D02*
Y1099641D01*
G01X806042Y796250D02*
Y1095542D01*
G01X823642Y1104201D02*
Y803546D01*
G01X819242Y1102377D02*
Y801722D01*
G01X814842Y799898D02*
Y1100553D01*
G01X838488Y808012D02*
X909800Y736700D01*
G01X838488Y1241182D02*
Y808012D01*
G01X803842Y795338D02*
Y1094630D01*
G01X825440Y1274034D02*
Y1567243D01*
G01X852488Y1246986D02*
X825440Y1274034D01*
G01X812953Y1269016D02*
Y1631063D01*
G01X840113Y1241856D02*
X812953Y1269016D01*
G01X809953Y1269717D02*
X838488Y1241182D01*
G01X809953Y1633575D02*
Y1269717D01*
G01X802418Y1366482D02*
Y1461604D01*
G01X804618Y1365570D02*
Y1462325D01*
G01X806800Y1364640D02*
Y1460344D01*
G01X800218Y1367394D02*
Y1464552D01*
G01X798018Y1368306D02*
Y1466787D01*
G01X802418Y1461604D02*
X802433Y1461619D01*
G01X804618Y1462325D02*
X806568Y1464275D01*
G01X806800Y1460344D02*
X806952Y1460496D01*
G01X800218Y1464552D02*
X800900Y1465234D01*
G01X798018Y1466787D02*
X800462Y1469231D01*
G01X844700Y1586503D02*
Y1615300D01*
G01X825440Y1567243D02*
X844700Y1586503D01*
G01Y1615300D02*
X847511Y1618111D01*
G01X812953Y1631063D02*
X826772Y1644882D01*
G01Y1650394D02*
X809953Y1633575D01*
G01X903337Y-100464D02*
X880481Y-77608D01*
G01X875356Y-79380D02*
Y-13819D01*
G01X926762Y-130786D02*
X875356Y-79380D01*
G01X877022Y-78747D02*
Y-13051D01*
G01X927436Y-129161D02*
X877022Y-78747D01*
G01X902663Y-102089D02*
X878688Y-78114D01*
G01D02*
Y-11215D01*
G01X929510Y-124286D02*
X882190Y-76966D01*
G01X930184Y-122661D02*
X883864Y-76341D01*
G01X880481Y-77608D02*
Y-9804D01*
G01X882190Y-76966D02*
Y-8011D01*
G01X883864Y-76341D02*
Y-6589D01*
G01X851533Y2698D02*
X849484Y649D01*
G01X867979Y2698D02*
X851533D01*
G01X880481Y-9804D02*
X867979Y2698D01*
G01X884915Y69D02*
X886322D01*
G01X849432Y35552D02*
X884915Y69D01*
G01X875356Y-13819D02*
X863142Y-1605D01*
G01X863312Y659D02*
X857513D01*
G01X877022Y-13051D02*
X863312Y659D01*
G01X886418Y-6687D02*
Y-7350D01*
G01X846182Y33549D02*
X886418Y-6687D01*
G01X884619Y3802D02*
X886427D01*
G01X851057Y37364D02*
X884619Y3802D01*
G01X878688Y-11215D02*
X867080Y393D01*
G01X885901Y-3735D02*
X886351D01*
G01X847807Y34359D02*
X885901Y-3735D01*
G01X882190Y-8011D02*
X873892Y287D01*
G01X872868Y4407D02*
X847340D01*
G01X883864Y-6589D02*
X872868Y4407D01*
G01X849432Y42085D02*
Y35552D01*
G01X891239Y50153D02*
Y85261D01*
G01X885448Y44362D02*
X891239Y50153D01*
G01X885448Y37380D02*
Y44362D01*
G01X846182Y40680D02*
Y33549D01*
G01X851057Y43023D02*
Y37364D01*
G01X847807Y41404D02*
Y34359D01*
G01X881549Y94951D02*
Y326304D01*
G01X891239Y85261D02*
X881549Y94951D01*
G01X868796Y249914D02*
Y224999D01*
G01X868696Y250014D02*
X868796Y249914D01*
G01X868696Y267654D02*
Y250014D01*
G01X847068Y286741D02*
Y230973D01*
G01X865546Y248566D02*
Y226347D01*
G01X865446Y248666D02*
X865546Y248566D01*
G01X865446Y262751D02*
Y248666D01*
G01X862196Y247318D02*
Y261296D01*
G01X862296Y247218D02*
X862196Y247318D01*
G01X862296Y227695D02*
Y247218D01*
G01X870421Y250588D02*
Y224325D01*
G01X870321Y250688D02*
X870421Y250588D01*
G01X870321Y269394D02*
Y250688D01*
G01X867171Y249240D02*
Y225673D01*
G01X867071Y249340D02*
X867171Y249240D01*
G01X867071Y266666D02*
Y249340D01*
G01X863821Y247992D02*
Y261970D01*
G01X863921Y247892D02*
X863821Y247992D01*
G01X863921Y227021D02*
Y247892D01*
G01X858158Y278192D02*
X868696Y267654D01*
G01X858158Y299961D02*
Y278192D01*
G01X853846Y274351D02*
X865446Y262751D01*
G01X853846Y293159D02*
Y274351D01*
G01X850596Y272896D02*
Y288823D01*
G01X862196Y261296D02*
X850596Y272896D01*
G01X860208Y279507D02*
X870321Y269394D01*
G01X860208Y302211D02*
Y279507D01*
G01X855545Y278192D02*
X867071Y266666D01*
G01X855545Y297095D02*
Y278192D01*
G01X852221Y273570D02*
Y291672D01*
G01X863821Y261970D02*
X852221Y273570D01*
G01X847338Y569011D02*
Y488422D01*
G01X848963Y567524D02*
Y487093D01*
G01X853067Y574740D02*
X847338Y569011D01*
G01X853067Y771009D02*
Y574740D01*
G01X848667Y769185D02*
Y576564D01*
G01X855267Y573828D02*
X848963Y567524D01*
G01X855267Y771921D02*
Y573828D01*
G01X850867Y770097D02*
Y575652D01*
G01X846467Y578337D02*
Y768273D01*
G01X915970Y752850D02*
X852488Y816332D01*
G01D02*
Y1246986D01*
G01X886988Y830385D02*
X940135Y777238D01*
G01X886988Y844957D02*
Y830385D01*
G01X891289Y838289D02*
X891200Y838200D01*
G01X891289Y855724D02*
Y838289D01*
G01X884523Y878404D02*
X896938Y865989D01*
G01X884523Y1262814D02*
Y878404D01*
G01X888962Y864301D02*
Y843262D01*
G01X875964Y877299D02*
X888962Y864301D01*
G01X875964Y1256718D02*
Y877299D01*
G01X886989Y844958D02*
X886988Y844957D01*
G01X886989Y850542D02*
Y844958D01*
G01X882988Y854543D02*
X886989Y850542D01*
G01X882988Y867212D02*
Y854543D01*
G01X874339Y875861D02*
X882988Y867212D01*
G01X874339Y1256044D02*
Y875861D01*
G01X879214Y878677D02*
X894965Y862926D01*
G01X879214Y1258066D02*
Y878677D01*
G01X891089Y855924D02*
X891289Y855724D01*
G01X891089Y857530D02*
Y855924D01*
G01X891289Y857730D02*
X891089Y857530D01*
G01X891289Y864273D02*
Y857730D01*
G01X877589Y877973D02*
X891289Y864273D01*
G01X877589Y1257392D02*
Y877973D01*
G01X882349Y896336D02*
X882333Y896320D01*
G01X882349Y1261026D02*
Y896336D01*
G01X860561Y1286776D02*
X884523Y1262814D01*
G01X875743Y1256939D02*
X875964Y1256718D01*
G01X875743Y1256940D02*
Y1256939D01*
G01X850805Y1281878D02*
X875743Y1256940D01*
G01X856524Y1286851D02*
X882349Y1261026D01*
G01X874118Y1256265D02*
X874339Y1256044D01*
G01X874118Y1256266D02*
Y1256265D01*
G01X849180Y1281204D02*
X874118Y1256266D01*
G01X878993Y1258287D02*
X879214Y1258066D01*
G01X878993Y1258288D02*
Y1258287D01*
G01X854055Y1283226D02*
X878993Y1258288D01*
G01X877368Y1257613D02*
X877589Y1257392D01*
G01X877368Y1257614D02*
Y1257613D01*
G01X852430Y1282552D02*
X877368Y1257614D01*
G01X860561Y1488811D02*
Y1286776D01*
G01X850805Y1513710D02*
Y1281878D01*
G01X856524Y1487515D02*
Y1286851D01*
G01X849180Y1514384D02*
Y1281204D01*
G01X854055Y1512362D02*
Y1283226D01*
G01X852430Y1513036D02*
Y1282552D01*
G01X893705Y1452159D02*
X902457Y1443407D01*
G01X893705Y1483646D02*
Y1452159D01*
G01X891505Y1451247D02*
X900257Y1442495D01*
G01X891505Y1484558D02*
Y1451247D01*
G01X862117Y1490367D02*
X860561Y1488811D01*
G01X862117Y1491973D02*
Y1490367D01*
G01X860561Y1493529D02*
X862117Y1491973D01*
G01X860561Y1499666D02*
Y1493529D01*
G01X858523Y1501704D02*
X860561Y1499666D01*
G01X858523Y1514531D02*
Y1501704D01*
G01X861937Y1517945D02*
X858523Y1514531D01*
G01X861937Y1549067D02*
Y1517945D01*
G01X903977Y1493918D02*
X893705Y1483646D01*
G01X857062Y1519967D02*
X850805Y1513710D01*
G01X860179Y1491170D02*
X856524Y1487515D01*
G01X897800Y1490853D02*
X891505Y1484558D01*
G01X850828Y1516032D02*
X849180Y1514384D01*
G01X850828Y1537732D02*
Y1516032D01*
G01X860312Y1518619D02*
X854055Y1512362D01*
G01X858687Y1519293D02*
X852430Y1513036D01*
G01X899876Y1587006D02*
X861937Y1549067D01*
G01X857062Y1552080D02*
Y1519967D01*
G01X888213Y1583231D02*
X857062Y1552080D01*
G01X853489Y1540393D02*
X850828Y1537732D01*
G01X853489Y1550806D02*
Y1540393D01*
G01X886338Y1583655D02*
X853489Y1550806D01*
G01X860312Y1550174D02*
Y1518619D01*
G01X895025Y1584887D02*
X860312Y1550174D01*
G01X858687Y1550985D02*
Y1519293D01*
G01X893130Y1585428D02*
X858687Y1550985D01*
G01X888213Y1600024D02*
Y1583231D01*
G01X890552Y1602363D02*
X888213Y1600024D01*
G01X893000Y1570650D02*
X896240Y1567410D01*
G01X893000Y1577069D02*
Y1570650D01*
G01X902033Y1586102D02*
X893000Y1577069D01*
G01X886338Y1603660D02*
Y1583655D01*
G01X890552Y1607874D02*
X886338Y1603660D01*
G01X893130Y1603530D02*
Y1585428D01*
G01X897638Y1608038D02*
X893130Y1603530D01*
G01X847511Y1618111D02*
X848032D01*
G01X1143165Y-130786D02*
X926762D01*
G01X1141678Y-129161D02*
X927436D01*
G01X928162Y-127536D02*
X902715Y-102089D01*
G01X1140191Y-127536D02*
X928162D01*
G01X903389Y-100464D02*
X903337D01*
G01X928836Y-125911D02*
X903389Y-100464D01*
G01X1138704Y-125911D02*
X928836D01*
G01X902715Y-102089D02*
X902663D01*
G01X1137217Y-124286D02*
X929510D01*
G01X1135730Y-122661D02*
X930184D01*
G01X954638Y739862D02*
X911081D01*
G01X909800Y736700D02*
X953200D01*
G01X942000Y752850D02*
X915970D01*
G01X940135Y777238D02*
X957462D01*
G01X896938Y839062D02*
X897000Y839000D01*
G01X896938Y865989D02*
Y839062D01*
G01X894965Y862926D02*
Y843500D01*
G01X955971Y1165929D02*
X914481Y1207419D01*
G01X954383Y1163617D02*
X912281Y1205719D01*
G01X954190Y1160310D02*
X910081Y1204419D01*
G01X921081Y1214342D02*
Y1391421D01*
G01X960996Y1174427D02*
X921081Y1214342D01*
G01X918881Y1210209D02*
Y1392333D01*
G01X957871Y1171219D02*
X918881Y1210209D01*
G01X914481Y1207419D02*
Y1394157D01*
G01X912281Y1205719D02*
Y1395069D01*
G01X916681Y1208919D02*
Y1393245D01*
G01X956798Y1168802D02*
X916681Y1208919D01*
G01X910081Y1204419D02*
Y1395981D01*
G01X909057Y1403257D02*
X895900Y1390100D01*
G01X909057Y1446143D02*
Y1403257D01*
G01X924457Y1394797D02*
Y1465212D01*
G01X921081Y1391421D02*
X924457Y1394797D01*
G01X906857Y1404557D02*
X896100Y1393800D01*
G01X906857Y1445231D02*
Y1404557D01*
G01X902457Y1407957D02*
X896100Y1401600D01*
G01X902457Y1443407D02*
Y1407957D01*
G01X922257Y1395709D02*
Y1463912D01*
G01X918881Y1392333D02*
X922257Y1395709D01*
G01X904657Y1406357D02*
X896200Y1397900D01*
G01X904657Y1444319D02*
Y1406357D01*
G01X917857Y1397533D02*
Y1457043D01*
G01X914481Y1394157D02*
X917857Y1397533D01*
G01X915657Y1398445D02*
Y1452943D01*
G01X912281Y1395069D02*
X915657Y1398445D01*
G01X920057Y1396621D02*
Y1457955D01*
G01X916681Y1393245D02*
X920057Y1396621D01*
G01X913457Y1399357D02*
Y1452031D01*
G01X910081Y1395981D02*
X913457Y1399357D01*
G01X911257Y1401057D02*
X896200Y1386000D01*
G01X911257Y1447055D02*
Y1401057D01*
G01X900257Y1409357D02*
X896200Y1405300D01*
G01X900257Y1442495D02*
Y1409357D01*
G01X900305Y1454895D02*
X909057Y1446143D01*
G01X900305Y1480910D02*
Y1454895D01*
G01X924457Y1465212D02*
X908542Y1481127D01*
G01X898105Y1453983D02*
X906857Y1445231D01*
G01X898105Y1481822D02*
Y1453983D01*
G01X922257Y1463912D02*
X908742Y1477427D01*
G01X895905Y1453071D02*
X904657Y1444319D01*
G01X895905Y1482734D02*
Y1453071D01*
G01X917857Y1457043D02*
X910000Y1464900D01*
G01X915657Y1452943D02*
X909400Y1459200D01*
G01X910851Y1467161D02*
X905500D01*
G01X920057Y1457955D02*
X910851Y1467161D01*
G01X906600Y1458888D02*
Y1461600D01*
G01X913457Y1452031D02*
X906600Y1458888D01*
G01X902505Y1455807D02*
X911257Y1447055D01*
G01X902505Y1479998D02*
Y1455807D01*
G01X910577Y1491182D02*
X900305Y1480910D01*
G01X910577Y1540477D02*
Y1491182D01*
G01X908377Y1492094D02*
X898105Y1481822D01*
G01X908377Y1636899D02*
Y1492094D01*
G01X903977Y1539023D02*
Y1493918D01*
G01X906177Y1493006D02*
X895905Y1482734D01*
G01X906177Y1539935D02*
Y1493006D01*
G01X912777Y1490270D02*
X902505Y1479998D01*
G01X912777Y1537452D02*
Y1490270D01*
G01X897800Y1542088D02*
Y1490853D01*
G01X915450Y1545350D02*
X910577Y1540477D01*
G01X915450Y1651290D02*
Y1545350D01*
G01X898610Y1544390D02*
X903977Y1539023D01*
G01X898610Y1569480D02*
Y1544390D01*
G01X900810Y1545302D02*
X906177Y1539935D01*
G01X900810Y1570590D02*
Y1545302D01*
G01X924059Y1548734D02*
X912777Y1537452D01*
G01X924059Y1647700D02*
Y1548734D01*
G01X896240Y1543648D02*
X897800Y1542088D01*
G01X896240Y1567410D02*
Y1543648D01*
G01X899876Y1596187D02*
Y1587006D01*
G01X897638Y1598425D02*
X899876Y1596187D01*
G01X895200Y1572890D02*
X898610Y1569480D01*
G01X895200Y1575762D02*
Y1572890D01*
G01X897038Y1577600D02*
X895200Y1575762D01*
G01X897400Y1574000D02*
X900810Y1570590D01*
G01X902033Y1628017D02*
Y1586102D01*
G01X895025Y1601324D02*
Y1584887D01*
G01X897638Y1603937D02*
X895025Y1601324D01*
G01X897638Y1608268D02*
Y1608038D01*
G01X913340Y1653400D02*
X915450Y1651290D01*
G01X907731Y1653400D02*
X913340D01*
G01X904725Y1650394D02*
X907731Y1653400D01*
G01X904725Y1640551D02*
X908377Y1636899D01*
G01X904725Y1630709D02*
X902033Y1628017D01*
G01X989050Y-60732D02*
Y-70850D01*
G01X994923Y-54859D02*
X989050Y-60732D01*
G01X983308Y372075D02*
X1002180Y353203D01*
G01X983308Y529701D02*
Y372075D01*
G01X994424Y540817D02*
X983308Y529701D01*
G01X973500Y643700D02*
X994424Y622776D01*
G01X973500Y761200D02*
Y643700D01*
G01X956900Y737600D02*
X954638Y739862D01*
G01X957462Y777238D02*
X973500Y761200D01*
G01X989494Y833191D02*
X1021706Y800979D01*
G01X989494Y968687D02*
Y833191D01*
G01X987869Y832517D02*
X1015099Y805287D01*
G01X987869Y968013D02*
Y832517D01*
G01X987734Y984492D02*
Y979575D01*
G01X975958Y996268D02*
X987734Y984492D01*
G01X968635Y989546D02*
X989494Y968687D01*
G01X963566Y992316D02*
X987869Y968013D01*
G01X975958Y1037694D02*
Y996268D01*
G01X968635Y1011755D02*
Y989546D01*
G01X971308Y1014428D02*
X968635Y1011755D01*
G01X971308Y1036257D02*
Y1014428D01*
G01X963566Y1011421D02*
Y992316D01*
G01X965960Y1013815D02*
X963566Y1011421D01*
G01X965960Y1034053D02*
Y1013815D01*
G01X993689Y1061782D02*
X965960Y1034053D01*
G01X997612Y1059348D02*
X975958Y1037694D01*
G01X995987Y1060936D02*
X971308Y1036257D01*
G01X987205Y1128975D02*
X997612Y1118568D01*
G01X987205Y1253248D02*
Y1128975D01*
G01X985580Y1128301D02*
X995987Y1117894D01*
G01X985580Y1254979D02*
Y1128301D01*
G01X980449Y1127070D02*
X993689Y1113830D01*
G01X980449Y1182035D02*
Y1127070D01*
G01X963000Y1174427D02*
X960996D01*
G01X962941Y1165929D02*
X955971D01*
G01X958870Y1163617D02*
X954383D01*
G01X967497Y1168802D02*
X956798D01*
G01X964537Y1160310D02*
X954190D01*
G01X979912Y1182572D02*
X980449Y1182035D01*
G01X979912Y1256313D02*
Y1182572D01*
G01X1068057Y1334100D02*
X987205Y1253248D01*
G01X1070930Y1340329D02*
X985580Y1254979D01*
G01X1072696Y1349097D02*
X979912Y1256313D01*
G01X1019082Y-61382D02*
Y-71000D01*
G01X1015200Y-57500D02*
X1019082Y-61382D01*
G01X1015200Y72552D02*
Y-57500D01*
G01X1019118Y-34382D02*
Y-23377D01*
G01X994923Y-37549D02*
Y-54859D01*
G01X1002180Y-30292D02*
X994923Y-37549D01*
G01X1002180Y41440D02*
Y-30292D01*
G01X1013513Y-56887D02*
X1000418Y-69982D01*
G01X1013513Y41354D02*
Y-56887D01*
G01X1030603Y-11892D02*
Y69369D01*
G01X1019118Y-23377D02*
X1030603Y-11892D01*
G01X1000143Y43477D02*
X1002180Y41440D01*
G01X1000143Y103463D02*
Y43477D01*
G01X1008094Y46773D02*
X1013513Y41354D01*
G01X1008094Y100167D02*
Y46773D01*
G01X1012538Y75214D02*
X1015200Y72552D01*
G01X1012538Y517205D02*
Y75214D01*
G01X1020250Y79722D02*
Y357188D01*
G01X1030603Y69369D02*
X1020250Y79722D01*
G01X1002180Y105500D02*
X1000143Y103463D01*
G01X1002180Y353203D02*
Y105500D01*
G01X1010821Y102894D02*
X1008094Y100167D01*
G01X1010821Y519781D02*
Y102894D01*
G01X1039500Y161058D02*
X1057480Y143078D01*
G01X1046200Y429858D02*
X1039500Y423158D01*
G01X1021706Y526373D02*
X1012538Y517205D01*
G01X1021706Y800979D02*
Y526373D01*
G01X994424Y622776D02*
Y540817D01*
G01X1015099Y524059D02*
X1010821Y519781D01*
G01X1015099Y805287D02*
Y524059D01*
G01X997612Y1118568D02*
Y1059348D01*
G01X995987Y1117894D02*
Y1060936D01*
G01X993689Y1113830D02*
Y1061782D01*
G01X1039201Y1411000D02*
X1028000D01*
G01X1048207Y1420006D02*
X1039201Y1411000D01*
G01X1038500Y1408000D02*
X1031500D01*
G01X1048881Y1418381D02*
X1038500Y1408000D01*
G01X1033000Y1416125D02*
X1041625D01*
G01X1079455Y-30677D02*
X1091322D01*
G01X1079455Y-30742D02*
Y-30677D01*
G01X1045886Y-19323D02*
X1043513Y-21696D01*
G01X1045886Y69340D02*
Y-19323D01*
G01X1057480Y80934D02*
X1045886Y69340D01*
G01X1057480Y143078D02*
Y80934D01*
G01X1039500Y423158D02*
Y161058D01*
G01X1041500Y421558D02*
Y382858D01*
G01X1052750Y432808D02*
X1041500Y421558D01*
G01X1052750Y457050D02*
Y432808D01*
G01X1046200Y443900D02*
Y429858D01*
G01X1043500Y446600D02*
X1046200Y443900D01*
G01X1087664Y491964D02*
X1052750Y457050D01*
G01X1087664Y748219D02*
Y491964D01*
G01X1098057Y758612D02*
X1087664Y748219D01*
G01X1080500Y951902D02*
X1098057Y934345D01*
G01X1080500Y1012000D02*
Y951902D01*
G01X1088500Y1020000D02*
X1080500Y1012000D01*
G01X1088510Y1192000D02*
X1075600Y1179090D01*
G01X1082400Y1173800D02*
X1093600Y1185000D01*
G01X1054164Y1173800D02*
X1082400D01*
G01X1053743Y1174221D02*
X1054164Y1173800D01*
G01X1080800Y1168000D02*
X1090800Y1178000D01*
G01X1046900Y1168000D02*
X1080800D01*
G01X1076032Y1198632D02*
Y1191144D01*
G01X1083800Y1206400D02*
X1076032Y1198632D01*
G01X1105969Y1206400D02*
X1083800D01*
G01X1076900Y1184100D02*
X1070000D01*
G01X1091900Y1199100D02*
X1076900Y1184100D01*
G01X1082000Y1271700D02*
X1087400Y1277100D01*
G01X1077300Y1271700D02*
X1082000D01*
G01X1087800Y1284400D02*
X1079500Y1276100D01*
G01X1087400Y1277100D02*
X1109901D01*
G01X1044481Y1324216D02*
X1042343D01*
G01X1077718Y1357453D02*
X1044481Y1324216D01*
G01X1106177Y1284400D02*
X1087800D01*
G01X1115720Y1334100D02*
X1068057D01*
G01X1051011Y1349992D02*
X1048251D01*
G01X1069019Y1368000D02*
X1051011Y1349992D01*
G01X1075700Y1368000D02*
X1069019D01*
G01X1090200Y1382500D02*
X1075700Y1368000D01*
G01X1082553Y1357453D02*
X1077718D01*
G01X1093500Y1368400D02*
X1082553Y1357453D01*
G01X1111612Y1340329D02*
X1070930D01*
G01X1054481Y1356326D02*
X1046372D01*
G01X1068155Y1370000D02*
X1054481Y1356326D01*
G01X1074731Y1370000D02*
X1068155D01*
G01X1089131Y1384400D02*
X1074731Y1370000D01*
G01X1077650Y1363350D02*
X1089600Y1375300D01*
G01X1075014Y1363350D02*
X1077650D01*
G01X1049280Y1337616D02*
X1075014Y1363350D01*
G01X1042343Y1337616D02*
X1049280D01*
G01X1051468Y1342668D02*
X1042443D01*
G01X1074600Y1365800D02*
X1051468Y1342668D01*
G01X1077100Y1365800D02*
X1074600D01*
G01X1088600Y1377300D02*
X1077100Y1365800D01*
G01X1116544Y1349097D02*
X1072696D01*
G01X1045444Y1330916D02*
X1042343D01*
G01X1074713Y1360185D02*
X1045444Y1330916D01*
G01X1081016Y1360185D02*
X1074713D01*
G01X1091131Y1370300D02*
X1081016Y1360185D01*
G01X1082088Y1420006D02*
X1048207D01*
G01X1088400Y1413694D02*
X1082088Y1420006D01*
G01X1081061Y1418381D02*
X1048881D01*
G01X1085700Y1413742D02*
X1081061Y1418381D01*
G01X1085700Y1399400D02*
Y1413742D01*
G01X1088401Y1396699D02*
X1085700Y1399400D01*
G01X1041625Y1416125D02*
X1048500Y1423000D01*
G01D02*
X1098818D01*
G01X1091825Y-89175D02*
X1089318Y-91682D01*
G01X1091825Y-32777D02*
Y-89175D01*
G01X1159153Y-99238D02*
X1135730Y-122661D01*
G01X1111253Y-31019D02*
Y-24047D01*
G01X1111254Y-31020D02*
X1111253Y-31019D01*
G01X1097033Y-29868D02*
X1136203Y9302D01*
G01X1097033Y-49167D02*
Y-29868D01*
G01X1094300Y-51900D02*
X1097033Y-49167D01*
G01X1094300Y-60300D02*
Y-51900D01*
G01X1134050Y9448D02*
X1091825Y-32777D01*
G01X1128765Y-34297D02*
X1146348Y-16714D01*
G01X1105328Y-31005D02*
Y-27673D01*
G01X1124024Y-30840D02*
X1143684Y-11180D01*
G01X1091322Y-30677D02*
X1132425Y10426D01*
G01X1101246Y-31005D02*
Y-28054D01*
G01X1111253Y-24047D02*
X1142800Y7500D01*
G01X1134050Y172850D02*
Y9448D01*
G01X1105328Y-27673D02*
X1140500Y7499D01*
G01X1132425Y10426D02*
Y174815D01*
G01X1101246Y-28054D02*
X1138500Y9200D01*
G01X1137100Y175900D02*
X1134050Y172850D01*
G01X1132425Y174815D02*
X1134110Y176500D01*
G01X1135475Y177865D02*
X1134110Y176500D01*
G01X1135475Y180332D02*
Y177865D01*
G01X1138475Y183332D02*
X1135475Y180332D01*
G01X1135410Y381990D02*
X1138475Y378925D01*
G01X1135410Y924178D02*
Y381990D01*
G01X1098057Y934345D02*
Y758612D01*
G01X1088851Y970737D02*
X1135410Y924178D01*
G01X1088851Y989519D02*
Y970737D01*
G01X1112043Y1020000D02*
X1088500D01*
G01X1115105Y1016938D02*
X1112043Y1020000D01*
G01X1092466Y993134D02*
X1088851Y989519D01*
G01X1110986Y993134D02*
X1092466D01*
G01X1113530Y995678D02*
X1110986Y993134D01*
G01X1133009Y999000D02*
X1139738Y1005729D01*
G01X1116852Y999000D02*
X1133009D01*
G01X1113530Y995678D02*
X1116852Y999000D01*
G01X1119000Y1087900D02*
X1143938Y1062962D01*
G01X1128500Y1088156D02*
X1158100Y1058556D01*
G01X1155900Y1056600D02*
X1123838Y1088662D01*
G01X1153700Y1055800D02*
X1121500Y1088000D01*
G01X1139738Y1063562D02*
X1117100Y1086200D01*
G01X1119000Y1110000D02*
Y1087900D01*
G01X1157637Y1148637D02*
X1119000Y1110000D01*
G01X1128500Y1096500D02*
Y1088156D01*
G01X1125000Y1100000D02*
X1128500Y1096500D01*
G01X1123600Y1100000D02*
X1125000D01*
G01X1123838Y1088662D02*
Y1092800D01*
G01X1162000Y1071984D02*
X1134103Y1099881D01*
G01X1123400Y1096400D02*
X1123600D01*
G01X1121500Y1094500D02*
X1123400Y1096400D01*
G01X1121500Y1088000D02*
Y1094500D01*
G01X1117100Y1110600D02*
X1149608Y1143108D01*
G01X1117100Y1086200D02*
Y1110600D01*
G01X1133783Y1096283D02*
X1133981D01*
G01X1131000Y1093500D02*
X1133783Y1096283D01*
G01X1131000Y1089000D02*
Y1093500D01*
G01X1160300Y1059700D02*
X1131000Y1089000D01*
G01X1134002Y1092600D02*
X1137400D01*
G01X1115105Y1174621D02*
Y1174430D01*
G01X1111726Y1178000D02*
X1115105Y1174621D01*
G01X1090800Y1178000D02*
X1111726D01*
G01X1109593Y1202776D02*
X1105969Y1206400D01*
G01X1110120Y1199100D02*
X1091900D01*
G01X1113530Y1195690D02*
X1110120Y1199100D01*
G01X1106196Y1192000D02*
X1088510D01*
G01X1109593Y1188603D02*
X1106196Y1192000D01*
G01X1110046Y1185000D02*
X1113530Y1181516D01*
G01X1093600Y1185000D02*
X1110046D01*
G01X1109901Y1277100D02*
X1113530Y1280729D01*
G01X1109593Y1287816D02*
X1106177Y1284400D01*
G01X1119042Y1337422D02*
X1115720Y1334100D01*
G01X1110650Y1368400D02*
X1093500D01*
G01X1115105Y1372855D02*
X1110650Y1368400D01*
G01X1115105Y1343822D02*
X1111612Y1340329D01*
G01X1115105Y1344508D02*
Y1343822D01*
G01X1119042Y1351595D02*
X1116544Y1349097D01*
G01X1107125Y1370300D02*
X1091131D01*
G01X1109593Y1372768D02*
X1107125Y1370300D01*
G01X1109593Y1372855D02*
Y1372768D01*
G01X1088400Y1400725D02*
Y1413694D01*
G01X1090525Y1398600D02*
X1088400Y1400725D01*
G01X1114500Y1398600D02*
X1090525D01*
G01X1118985Y1394115D02*
X1114500Y1398600D01*
G01X1119042Y1394115D02*
X1118985D01*
G01X1113500Y1382500D02*
X1090200D01*
G01X1115105Y1384105D02*
X1113500Y1382500D01*
G01X1115105Y1387028D02*
Y1384105D01*
G01X1106725Y1384400D02*
X1089131D01*
G01X1109353Y1387028D02*
X1106725Y1384400D01*
G01X1109593Y1387028D02*
X1109353D01*
G01X1110946Y1396699D02*
X1088401D01*
G01X1113530Y1394115D02*
X1110946Y1396699D01*
G01X1114400Y1375300D02*
X1119042Y1379942D01*
G01X1089600Y1375300D02*
X1114400D01*
G01X1135000Y1376500D02*
X1140000Y1371500D01*
G01X1122500Y1376500D02*
X1135000D01*
G01X1119058Y1379942D02*
X1122500Y1376500D01*
G01X1119042Y1379942D02*
X1119058D01*
G01X1110400Y1377300D02*
X1088600D01*
G01X1113042Y1379942D02*
X1110400Y1377300D01*
G01X1113530Y1379942D02*
X1113042D01*
G01X1117118Y1404700D02*
X1113530Y1408288D01*
G01X1133275Y1404700D02*
X1117118D01*
G01X1142800Y1395175D02*
X1133275Y1404700D01*
G01X1098818Y1423000D02*
X1113530Y1408288D01*
G01X1170153Y-103798D02*
X1143165Y-130786D01*
G01X1167953Y-102886D02*
X1141678Y-129161D01*
G01X1165753Y-101974D02*
X1140191Y-127536D01*
G01X1163553Y-101062D02*
X1138704Y-125911D01*
G01X1163553Y119757D02*
Y-101062D01*
G01X1170153Y117021D02*
Y-103798D01*
G01X1167953Y117933D02*
Y-102886D01*
G01X1165753Y118845D02*
Y-101974D01*
G01X1161353Y-100150D02*
X1137217Y-124286D01*
G01X1161353Y120669D02*
Y-100150D01*
G01X1159153Y121581D02*
Y-99238D01*
G01X1148548Y-29458D02*
X1146768Y-31238D01*
G01X1148548Y419415D02*
Y-29458D01*
G01X1156799Y-31532D02*
Y229127D01*
G01X1151137Y-37194D02*
X1156799Y-31532D01*
G01X1142621Y-37194D02*
X1151137D01*
G01X1142293Y-37522D02*
X1142621Y-37194D01*
G01X1151228Y-30197D02*
Y-28629D01*
G01X1148148Y-33277D02*
X1151228Y-30197D01*
G01X1141914Y-33277D02*
X1148148D01*
G01X1139808Y-31171D02*
X1141914Y-33277D01*
G01X1154599Y-30253D02*
X1149699Y-35153D01*
G01X1154599Y228215D02*
Y-30253D01*
G01X1142800Y7500D02*
Y174637D01*
G01X1136203Y9302D02*
Y167600D01*
G01X1146348Y-16714D02*
Y173145D01*
G01X1140500Y7499D02*
Y171400D01*
G01X1144425Y6826D02*
Y173521D01*
G01X1143684Y6085D02*
X1144425Y6826D01*
G01X1143684Y-11180D02*
Y6085D01*
G01X1151228Y-26080D02*
Y419895D01*
G01X1151215Y-26093D02*
X1151228Y-26080D01*
G01X1151215Y-28616D02*
Y-26093D01*
G01X1151228Y-28629D02*
X1151215Y-28616D01*
G01X1138500Y9200D02*
Y173500D01*
G01X1163399Y119757D02*
X1163553D01*
G01X1163399Y231863D02*
Y119757D01*
G01X1169999Y117021D02*
X1170153D01*
G01X1169999Y232973D02*
Y117021D01*
G01X1167799Y117933D02*
X1167953D01*
G01X1167799Y232874D02*
Y117933D01*
G01X1165599Y118845D02*
X1165753D01*
G01X1165599Y232775D02*
Y118845D01*
G01X1161199Y120669D02*
X1161353D01*
G01X1161199Y230951D02*
Y120669D01*
G01X1158999Y121581D02*
X1159153D01*
G01X1158999Y230039D02*
Y121581D01*
G01X1137100Y179658D02*
Y175900D01*
G01X1142142Y184700D02*
X1137100Y179658D01*
G01X1142142Y1000415D02*
Y184700D01*
G01X1146348Y176129D02*
Y419415D01*
G01X1146363Y176114D02*
X1146348Y176129D01*
G01X1146363Y173160D02*
Y176114D01*
G01X1146348Y173145D02*
X1146363Y173160D01*
G01X1144148Y176030D02*
Y419514D01*
G01X1144738Y175440D02*
X1144148Y176030D01*
G01X1144738Y173834D02*
Y175440D01*
G01X1144425Y173521D02*
X1144738Y173834D01*
G01X1138475Y378925D02*
Y183332D01*
G01X1140550Y175550D02*
Y179200D01*
G01X1138500Y173500D02*
X1140550Y175550D01*
G01X1159955Y235307D02*
X1163399Y231863D01*
G01X1159955Y450465D02*
Y235307D01*
G01X1164830Y238142D02*
X1169999Y232973D01*
G01X1164830Y446004D02*
Y238142D01*
G01X1163205Y237468D02*
X1167799Y232874D01*
G01X1163205Y447491D02*
Y237468D01*
G01X1155080Y230846D02*
Y454926D01*
G01X1156799Y229127D02*
X1155080Y230846D01*
G01X1153455Y229359D02*
X1154599Y228215D01*
G01X1153455Y456413D02*
Y229359D01*
G01X1161580Y236794D02*
X1165599Y232775D01*
G01X1161580Y448978D02*
Y236794D01*
G01X1158330Y233820D02*
X1161199Y230951D01*
G01X1158330Y451952D02*
Y233820D01*
G01X1156705Y232333D02*
X1158999Y230039D01*
G01X1156705Y453439D02*
Y232333D01*
G01X1220750Y511260D02*
X1159955Y450465D01*
G01X1227350Y508524D02*
X1164830Y446004D01*
G01X1225150Y509436D02*
X1163205Y447491D01*
G01X1149056Y419923D02*
X1148548Y419415D01*
G01X1149056Y420022D02*
Y419923D01*
G01X1149630Y420596D02*
X1149056Y420022D01*
G01X1149630Y998938D02*
Y420596D01*
G01X1147430D02*
Y999850D01*
G01X1146856Y420022D02*
X1147430Y420596D01*
G01X1146856Y419923D02*
Y420022D01*
G01X1146348Y419415D02*
X1146856Y419923D01*
G01X1145230Y420596D02*
Y1000762D01*
G01X1144148Y419514D02*
X1145230Y420596D01*
G01X1151830D02*
Y998026D01*
G01X1151256Y420022D02*
X1151830Y420596D01*
G01X1151256Y419923D02*
Y420022D01*
G01X1151228Y419895D02*
X1151256Y419923D01*
G01X1222950Y510348D02*
X1161580Y448978D01*
G01X1218550Y512172D02*
X1158330Y451952D01*
G01X1216350Y513084D02*
X1156705Y453439D01*
G01X1155080Y454926D02*
X1214150Y513996D01*
G01X1211950Y514908D02*
X1153455Y456413D01*
G01X1143938Y1002211D02*
X1142142Y1000415D01*
G01X1143938Y1062962D02*
Y1002211D01*
G01X1158100Y1007408D02*
X1149630Y998938D01*
G01X1158100Y1058556D02*
Y1007408D01*
G01X1155900Y1008320D02*
Y1056600D01*
G01X1147430Y999850D02*
X1155900Y1008320D01*
G01X1153700Y1009232D02*
Y1055800D01*
G01X1145230Y1000762D02*
X1153700Y1009232D01*
G01X1139738Y1005729D02*
Y1063562D01*
G01X1160300Y1006496D02*
Y1059700D01*
G01X1151830Y998026D02*
X1160300Y1006496D01*
G01X1171764Y1071613D02*
X1220750Y1022627D01*
G01X1171764Y1074797D02*
Y1071613D01*
G01X1145875Y1100686D02*
X1171764Y1074797D01*
G01X1177019Y1074881D02*
X1227350Y1024550D01*
G01X1177019Y1082481D02*
Y1074881D01*
G01X1149984Y1109516D02*
X1177019Y1082481D01*
G01X1175054Y1073734D02*
X1225150Y1023638D01*
G01X1175054Y1078446D02*
Y1073734D01*
G01X1147500Y1106000D02*
X1175054Y1078446D01*
G01X1162000Y1066000D02*
Y1071984D01*
G01X1214150Y1013850D02*
X1162000Y1066000D01*
G01X1159500Y1065388D02*
X1211950Y1012938D01*
G01X1159500Y1070500D02*
Y1065388D01*
G01X1137400Y1092600D02*
X1159500Y1070500D01*
G01X1173389Y1072287D02*
X1222950Y1022726D01*
G01X1173389Y1077163D02*
Y1072287D01*
G01X1152880Y1097672D02*
X1173389Y1077163D01*
G01X1152682Y1086770D02*
X1218550Y1020902D01*
G01X1143550Y1092790D02*
X1216350Y1019990D01*
G01X1145875Y1121625D02*
Y1100686D01*
G01X1144843Y1122657D02*
X1145875Y1121625D01*
G01X1140364Y1122657D02*
X1144843D01*
G01X1139524Y1121817D02*
X1140364Y1122657D01*
G01X1149984Y1115804D02*
Y1109516D01*
G01X1147500Y1123500D02*
Y1106000D01*
G01X1146250Y1124750D02*
X1147500Y1123500D01*
G01X1137436Y1124750D02*
X1146250D01*
G01X1152682Y1091138D02*
Y1086770D01*
G01X1143550Y1120317D02*
Y1092790D01*
G01X1157637Y1225559D02*
Y1148637D01*
G01X1149608Y1143108D02*
Y1228988D01*
G01X1149823Y1233373D02*
X1157637Y1225559D01*
G01X1149608Y1228988D02*
X1150420Y1229800D01*
G01X1144000Y1325848D02*
Y1310000D01*
G01X1187101Y1285399D02*
X1142800Y1329700D01*
G01X1140000Y1329848D02*
X1144000Y1325848D01*
G01X1140000Y1371500D02*
Y1329848D01*
G01X1142800Y1329700D02*
Y1395175D01*
G01X1217212Y182659D02*
Y222397D01*
G01X1215795Y181242D02*
X1217212Y182659D01*
G01X1285967Y191433D02*
X1215600Y261800D01*
G01X1213609Y254917D02*
Y380244D01*
G01X1225630Y242896D02*
X1213609Y254917D01*
G01X1225630Y230815D02*
Y242896D01*
G01X1217212Y222397D02*
X1225630Y230815D01*
G01X1213609Y380244D02*
X1238160Y404795D01*
G01X1220750Y1022627D02*
Y511260D01*
G01X1227350Y1024550D02*
Y508524D01*
G01X1225150Y1023638D02*
Y509436D01*
G01X1214150Y513996D02*
Y1013850D01*
G01X1211950Y1012938D02*
Y514908D01*
G01X1222950Y1022726D02*
Y510348D01*
G01X1218550Y1020902D02*
Y512172D01*
G01X1216350Y1019990D02*
Y513084D01*
G01X1231226Y678438D02*
Y936126D01*
G01X1239362Y670302D02*
X1231226Y678438D01*
G01X1229288Y677635D02*
Y1025473D01*
G01X1237262Y669661D02*
X1229288Y677635D01*
G01X1231226Y936126D02*
X1235600Y940500D01*
G01Y1021902D02*
X1205132Y1052370D01*
G01X1229288Y1025473D02*
X1187101Y1067660D01*
G01X1205132Y1052370D02*
Y1227433D01*
G01X1232842Y1073658D02*
X1252400Y1054100D01*
G01X1232842Y1140722D02*
Y1073658D01*
G01X1187101Y1067660D02*
Y1285399D01*
G01X1205132Y1227433D02*
X1205303Y1227604D01*
G01X1255761Y271861D02*
X1250500Y266600D01*
G01X1255761Y573504D02*
Y271861D01*
G01X1257962Y303984D02*
Y577343D01*
G01X1288850Y273096D02*
X1257962Y303984D01*
G01X1286997Y272178D02*
X1262075Y297100D01*
G01X1259587Y304658D02*
Y578017D01*
G01X1290475Y273770D02*
X1259587Y304658D01*
G01X1266816Y304326D02*
Y581400D01*
G01X1296300Y274842D02*
X1266816Y304326D01*
G01X1262837Y306006D02*
X1294367Y274476D01*
G01X1262837Y580665D02*
Y306006D01*
G01X1261212Y305332D02*
X1292600Y273944D01*
G01X1261212Y579991D02*
Y305332D01*
G01X1272106Y301743D02*
X1281928Y291921D01*
G01X1272106Y303549D02*
Y301743D01*
G01X1270448Y305207D02*
X1272106Y303549D01*
G01X1270448Y580600D02*
Y305207D01*
G01X1272073Y305881D02*
Y581400D01*
G01X1273731Y304223D02*
X1272073Y305881D01*
G01X1273731Y302417D02*
Y304223D01*
G01X1282601Y293547D02*
X1273731Y302417D01*
G01X1238160Y404795D02*
Y522540D01*
G01X1278523Y472475D02*
Y577677D01*
G01X1331667Y419331D02*
X1278523Y472475D01*
G01X1280461Y473279D02*
Y578698D01*
G01X1338460Y415280D02*
X1280461Y473279D01*
G01X1239362Y524168D02*
Y670302D01*
G01X1237262Y523438D02*
Y669661D01*
G01X1238160Y522540D02*
X1237262Y523438D01*
G01X1253511Y517606D02*
Y572642D01*
G01X1247989Y581276D02*
X1255761Y573504D01*
G01X1247989Y670999D02*
Y581276D01*
G01X1250237Y585068D02*
Y692117D01*
G01X1257962Y577343D02*
X1250237Y585068D01*
G01X1267662Y588538D02*
Y698613D01*
G01X1278523Y577677D02*
X1267662Y588538D01*
G01X1251862Y585742D02*
Y691443D01*
G01X1259587Y578017D02*
X1251862Y585742D01*
G01X1262787Y585429D02*
Y679354D01*
G01X1266816Y581400D02*
X1262787Y585429D01*
G01X1260700Y582802D02*
X1262837Y580665D01*
G01X1260700Y603960D02*
Y582802D01*
G01X1257810Y583393D02*
X1261212Y579991D01*
G01X1257810Y604551D02*
Y583393D01*
G01X1264412Y586636D02*
X1270448Y580600D01*
G01X1264412Y680728D02*
Y586636D01*
G01X1245789Y580364D02*
Y670087D01*
G01X1253511Y572642D02*
X1245789Y580364D01*
G01X1270206Y588953D02*
Y674446D01*
G01X1280461Y578698D02*
X1270206Y588953D01*
G01X1266037Y587436D02*
Y681402D01*
G01X1272073Y581400D02*
X1266037Y587436D01*
G01X1258062Y606598D02*
X1260700Y603960D01*
G01X1258062Y680043D02*
Y606598D01*
G01X1256437Y605924D02*
X1257810Y604551D01*
G01X1256437Y681329D02*
Y605924D01*
G01X1239443Y679545D02*
X1247989Y670999D01*
G01X1239443Y929943D02*
Y679545D01*
G01X1252924Y694804D02*
Y870732D01*
G01X1250237Y692117D02*
X1252924Y694804D01*
G01X1254549Y694130D02*
Y870058D01*
G01X1251862Y691443D02*
X1254549Y694130D01*
G01X1260600Y681541D02*
Y799188D01*
G01X1262787Y679354D02*
X1260600Y681541D01*
G01X1258975Y680956D02*
X1258062Y680043D01*
G01X1258975Y799862D02*
Y680956D01*
G01X1257350Y682242D02*
X1256437Y681329D01*
G01X1257350Y800536D02*
Y682242D01*
G01X1263210Y681930D02*
X1264412Y680728D01*
G01X1263210Y681931D02*
Y681930D01*
G01X1262225Y682916D02*
X1263210Y681931D01*
G01X1262225Y798514D02*
Y682916D01*
G01X1237243Y678633D02*
Y938243D01*
G01X1245789Y670087D02*
X1237243Y678633D01*
G01X1274200Y678440D02*
Y702800D01*
G01X1270206Y674446D02*
X1274200Y678440D01*
G01X1263850Y683590D02*
Y797840D01*
G01X1264835Y682605D02*
X1263850Y683590D01*
G01X1264835Y682604D02*
Y682605D01*
G01X1266037Y681402D02*
X1264835Y682604D01*
G01X1268400Y732463D02*
X1291194Y755257D01*
G01X1268400Y716100D02*
Y732463D01*
G01X1270873Y739726D02*
Y870974D01*
G01X1266462Y735315D02*
X1270873Y739726D01*
G01X1266462Y715297D02*
Y735315D01*
G01X1267662Y714097D02*
X1266462Y715297D01*
G01X1267662Y700553D02*
Y714097D01*
G01X1267829Y700386D02*
X1267662Y700553D01*
G01X1267829Y698780D02*
Y700386D01*
G01X1267662Y698613D02*
X1267829Y698780D01*
G01X1274200Y702800D02*
X1294250Y722850D01*
G01X1265500Y804088D02*
Y874112D01*
G01X1260600Y799188D02*
X1265500Y804088D01*
G01X1260700Y801587D02*
X1258975Y799862D01*
G01X1260700Y871611D02*
Y801587D01*
G01X1257810Y800996D02*
X1257350Y800536D01*
G01X1257810Y871020D02*
Y800996D01*
G01X1267623Y803912D02*
X1262225Y798514D01*
G01X1267623Y872323D02*
Y803912D01*
G01X1269248Y803238D02*
Y871648D01*
G01X1263850Y797840D02*
X1269248Y803238D01*
G01X1264269Y882077D02*
Y981248D01*
G01X1252924Y870732D02*
X1264269Y882077D01*
G01X1270873Y870974D02*
X1286633Y886734D01*
G01X1266207Y881716D02*
Y987992D01*
G01X1254549Y870058D02*
X1266207Y881716D01*
G01X1274413Y883025D02*
Y984613D01*
G01X1265500Y874112D02*
X1274413Y883025D01*
G01X1271296Y882207D02*
X1260700Y871611D01*
G01X1271296Y986867D02*
Y882207D01*
G01X1268378Y881588D02*
X1257810Y871020D01*
G01X1268378Y990608D02*
Y881588D01*
G01X1276351Y881051D02*
X1267623Y872323D01*
G01X1276351Y1056087D02*
Y881051D01*
G01X1279599Y881999D02*
Y976407D01*
G01X1269248Y871648D02*
X1279599Y881999D01*
G01X1243200Y933700D02*
X1239443Y929943D01*
G01X1259808Y927260D02*
Y1044892D01*
G01X1235600Y940500D02*
Y1021902D01*
G01X1253338Y980784D02*
Y1044356D01*
G01X1256142Y972314D02*
X1253975Y970147D01*
G01X1256142Y1029316D02*
Y972314D01*
G01X1240583Y941583D02*
Y1023317D01*
G01X1237243Y938243D02*
X1240583Y941583D01*
G01X1263618Y990581D02*
Y990606D01*
G01X1266207Y987992D02*
X1263618Y990581D01*
G01X1240583Y1023317D02*
X1239900Y1024000D01*
G01X1257000Y1047700D02*
Y1165700D01*
G01X1259808Y1044892D02*
X1257000Y1047700D01*
G01X1254800Y1045818D02*
Y1269600D01*
G01X1253338Y1044356D02*
X1254800Y1045818D01*
G01X1272755Y1059683D02*
X1276351Y1056087D01*
G01X1272755Y1137293D02*
Y1059683D01*
G01X1257000Y1165700D02*
X1260300Y1169000D01*
G01X1240276Y1139779D02*
Y1356700D01*
G01X1240314Y1139741D02*
X1240276Y1139779D01*
G01X1323829Y55929D02*
X1331159Y63259D01*
G01X1323155Y53862D02*
X1306500Y70517D01*
G01X1339203Y53862D02*
X1323155D01*
G01X1326496Y101252D02*
Y128870D01*
G01X1333281Y94467D02*
X1326496Y101252D01*
G01X1323762Y101375D02*
Y123578D01*
G01X1331159Y93978D02*
X1323762Y101375D01*
G01X1328121Y101971D02*
Y128196D01*
G01X1336034Y94058D02*
X1328121Y101971D01*
G01X1306500Y101575D02*
Y151320D01*
G01X1306501Y101574D02*
X1306500Y101575D01*
G01X1306501Y99968D02*
Y101574D01*
G01X1306500Y99967D02*
X1306501Y99968D01*
G01X1306500Y94412D02*
Y99967D01*
G01X1306290Y94202D02*
X1306500Y94412D01*
G01X1306290Y92596D02*
Y94202D01*
G01X1306500Y92386D02*
X1306290Y92596D01*
G01X1306500Y85113D02*
Y92386D01*
G01X1306501Y85112D02*
X1306500Y85113D01*
G01X1306501Y83506D02*
Y85112D01*
G01X1306500Y83505D02*
X1306501Y83506D01*
G01X1306500Y70517D02*
Y83505D01*
G01X1319019Y136347D02*
Y170334D01*
G01X1326496Y128870D02*
X1319019Y136347D01*
G01X1317394Y163136D02*
X1299675Y180855D01*
G01X1317394Y129946D02*
Y163136D01*
G01X1323762Y123578D02*
X1317394Y129946D01*
G01X1320644Y137021D02*
Y171008D01*
G01X1328122Y129543D02*
X1320644Y137021D01*
G01X1328122Y128197D02*
Y129543D01*
G01X1328121Y128196D02*
X1328122Y128197D01*
G01X1326158Y143371D02*
Y173752D01*
G01X1328118Y141411D02*
X1326158Y143371D01*
G01X1328118Y136444D02*
Y141411D01*
G01X1332997Y131565D02*
X1328118Y136444D01*
G01X1326492Y135771D02*
X1331372Y130891D01*
G01X1326492Y137117D02*
Y135771D01*
G01X1326493Y137118D02*
X1326492Y137117D01*
G01X1326493Y140361D02*
Y137118D01*
G01X1324533Y142321D02*
X1326493Y140361D01*
G01X1324533Y171717D02*
Y142321D01*
G01X1322269Y137695D02*
X1329747Y130217D01*
G01X1322269Y171682D02*
Y137695D01*
G01X1328179Y143649D02*
X1330339Y141489D01*
G01X1328179Y174267D02*
Y143649D01*
G01X1306500Y151320D02*
X1285967Y171853D01*
G01X1301300Y188053D02*
Y253154D01*
G01X1319019Y170334D02*
X1301300Y188053D01*
G01X1299675Y180855D02*
Y252283D01*
G01X1324470Y210630D02*
Y293153D01*
G01X1327762Y207338D02*
X1324470Y210630D01*
G01X1327762Y180375D02*
Y207338D01*
G01X1331866Y176271D02*
X1327762Y180375D01*
G01X1302925Y188727D02*
Y253828D01*
G01X1320644Y171008D02*
X1302925Y188727D01*
G01X1322887Y203215D02*
X1307800Y218302D01*
G01X1322887Y177023D02*
Y203215D01*
G01X1326158Y173752D02*
X1322887Y177023D01*
G01X1306175Y190075D02*
X1324533Y171717D01*
G01X1306175Y255176D02*
Y190075D01*
G01X1304550Y189401D02*
X1322269Y171682D01*
G01X1304550Y254502D02*
Y189401D01*
G01X1324512Y177934D02*
X1328179Y174267D01*
G01X1324512Y203889D02*
Y177934D01*
G01X1309425Y218976D02*
X1324512Y203889D01*
G01X1285967Y171853D02*
Y191433D01*
G01X1326137Y204563D02*
X1311050Y219650D01*
G01X1326137Y178992D02*
Y204563D01*
G01X1330008Y175121D02*
X1326137Y178992D01*
G01X1301300Y253154D02*
X1288850Y265604D01*
G01X1299675Y252283D02*
X1286997Y264961D01*
G01X1302925Y253828D02*
X1290475Y266278D01*
G01X1307800Y255850D02*
X1296300Y267350D01*
G01X1307800Y218302D02*
Y255850D01*
G01X1294367Y266984D02*
X1306175Y255176D01*
G01X1292600Y266452D02*
X1304550Y254502D01*
G01X1309425Y258175D02*
Y218976D01*
G01X1304945Y262655D02*
X1309425Y258175D01*
G01X1311050Y258849D02*
X1306804Y263095D01*
G01X1311050Y219650D02*
Y258849D01*
G01X1288850Y265604D02*
Y273096D01*
G01X1286997Y264961D02*
Y272178D01*
G01X1324470Y293153D02*
X1331667Y300350D01*
G01X1290475Y266278D02*
Y273770D01*
G01X1296300Y267350D02*
Y274842D01*
G01X1294367Y274476D02*
Y266984D01*
G01X1292600Y273944D02*
Y266452D01*
G01X1304945Y270710D02*
Y262655D01*
G01X1283734Y291921D02*
X1304945Y270710D01*
G01X1281928Y291921D02*
X1283734D01*
G01X1284407Y293547D02*
X1282601D01*
G01X1306804Y271150D02*
X1284407Y293547D01*
G01X1306804Y263095D02*
Y271150D01*
G01X1293125Y478530D02*
X1351124Y420531D01*
G01X1349499Y419857D02*
X1291500Y477856D01*
G01X1355487Y423016D02*
X1297488Y481015D01*
G01X1294750Y479204D02*
X1352749Y421205D01*
G01X1358487Y424259D02*
X1300488Y482258D01*
G01X1289875Y477182D02*
X1347874Y419183D01*
G01X1293125Y673527D02*
Y478530D01*
G01X1320876Y481286D02*
Y629559D01*
G01X1384713Y417449D02*
X1320876Y481286D01*
G01X1291500Y477856D02*
Y674201D01*
G01X1297488Y481015D02*
Y671718D01*
G01X1303226Y483393D02*
Y627010D01*
G01X1361225Y425394D02*
X1303226Y483393D01*
G01X1318938Y480483D02*
Y629920D01*
G01X1380100Y419321D02*
X1318938Y480483D01*
G01X1305562Y483356D02*
Y627047D01*
G01X1362850Y426068D02*
X1305562Y483356D01*
G01X1294750Y672853D02*
Y479204D01*
G01X1300488Y482258D02*
Y670475D01*
G01X1289875Y585210D02*
Y477182D01*
G01X1328552Y543848D02*
X1353500Y518900D01*
G01X1328552Y622901D02*
Y543848D01*
G01X1326352Y532048D02*
X1338100Y520300D01*
G01X1326352Y623000D02*
Y532048D01*
G01X1287168Y587917D02*
X1289875Y585210D01*
G01X1287168Y598666D02*
Y587917D01*
G01X1289781Y601279D02*
X1287168Y598666D01*
G01X1320876Y629559D02*
X1336600Y645283D01*
G01X1330534Y624883D02*
X1328552Y622901D01*
G01X1317638Y641422D02*
Y665990D01*
G01X1303226Y627010D02*
X1317638Y641422D01*
G01X1328909Y625557D02*
X1326352Y623000D01*
G01X1328909Y630590D02*
Y625557D01*
G01X1341550Y643231D02*
X1328909Y630590D01*
G01X1326688Y637670D02*
Y662238D01*
G01X1318938Y629920D02*
X1326688Y637670D01*
G01X1319263Y640748D02*
Y665316D01*
G01X1305562Y627047D02*
X1319263Y640748D01*
G01X1289781Y621631D02*
Y601279D01*
G01X1287168Y624244D02*
X1289781Y621631D01*
G01X1287168Y672168D02*
Y624244D01*
G01X1338700Y719102D02*
X1293125Y673527D01*
G01X1291500Y674201D02*
X1336238Y718939D01*
G01X1297488Y671718D02*
X1344062Y718292D01*
G01X1317638Y665990D02*
X1331349Y679701D01*
G01X1326688Y662238D02*
X1340674Y676224D01*
G01X1319263Y665316D02*
X1333249Y679302D01*
G01X1340638Y718741D02*
X1294750Y672853D01*
G01X1300488Y670475D02*
X1347600Y717587D01*
G01X1334300Y719300D02*
X1287168Y672168D01*
G01X1294250Y722850D02*
Y762970D01*
G01X1291194Y763893D02*
X1341219Y813918D01*
G01X1291194Y755257D02*
Y763893D01*
G01X1294250Y762970D02*
X1346080Y814800D01*
G01X1286633Y886734D02*
Y967747D01*
G01X1312767Y1061167D02*
Y885535D01*
G01X1286000Y968380D02*
Y982200D01*
G01X1286633Y967747D02*
X1286000Y968380D01*
G01X1317400Y1065800D02*
X1312767Y1061167D01*
G01X1317400Y1068000D02*
Y1065800D01*
G01X1331159Y63259D02*
Y93978D01*
G01X1359350Y66350D02*
X1363758Y70758D01*
G01X1357238Y71897D02*
X1339203Y53862D01*
G01X1354494Y116403D02*
X1348641Y110550D01*
G01X1333281Y85133D02*
Y94467D01*
G01X1340338Y115049D02*
Y139719D01*
G01X1338215Y112926D02*
X1340338Y115049D01*
G01X1338215Y107586D02*
Y112926D01*
G01X1336034Y82542D02*
Y94058D01*
G01X1332996Y104463D02*
Y126174D01*
G01X1343521Y93938D02*
X1332996Y104463D01*
G01X1343521Y85472D02*
Y93938D01*
G01X1363758Y70758D02*
Y123018D01*
G01X1340961Y94132D02*
Y78811D01*
G01X1331371Y103722D02*
X1340961Y94132D01*
G01X1331371Y126848D02*
Y103722D01*
G01X1345078Y103866D02*
X1347607Y101337D01*
G01X1345078Y112043D02*
Y103866D01*
G01X1348050Y115015D02*
X1345078Y112043D01*
G01X1348050Y133047D02*
Y115015D01*
G01X1337972Y79481D02*
X1334383Y75892D01*
G01X1337972Y94510D02*
Y79481D01*
G01X1329746Y102736D02*
X1337972Y94510D01*
G01X1329746Y127522D02*
Y102736D01*
G01X1346081Y93677D02*
Y80671D01*
G01X1334621Y105137D02*
X1346081Y93677D01*
G01X1334621Y125500D02*
Y105137D01*
G01X1357238Y80371D02*
Y71897D01*
G01X1358355Y81488D02*
X1357238Y80371D01*
G01X1356119Y111836D02*
X1350779Y106496D01*
G01X1356119Y131331D02*
Y111836D01*
G01X1346703Y107372D02*
X1352351Y101724D01*
G01X1346703Y111369D02*
Y107372D01*
G01X1349675Y114341D02*
X1346703Y111369D01*
G01X1349675Y132373D02*
Y114341D01*
G01X1336246Y106142D02*
Y124826D01*
G01X1348641Y93747D02*
X1336246Y106142D01*
G01X1348641Y83326D02*
Y93747D01*
G01X1354494Y132005D02*
Y116403D01*
G01X1356147Y133658D02*
X1354494Y132005D01*
G01X1356147Y145556D02*
Y133658D01*
G01X1345865Y155838D02*
X1356147Y145556D01*
G01X1345865Y293893D02*
Y155838D01*
G01X1393816Y130584D02*
X1358573Y165827D01*
G01X1331866Y148191D02*
Y176271D01*
G01X1340338Y139719D02*
X1331866Y148191D01*
G01X1415017Y124972D02*
X1370275Y169714D01*
G01X1391700Y130201D02*
X1355991Y165910D01*
G01X1332997Y126175D02*
Y131565D01*
G01X1332996Y126174D02*
X1332997Y126175D01*
G01X1363758Y123018D02*
X1364017Y123277D01*
G01X1331372Y126849D02*
X1331371Y126848D01*
G01X1331372Y130891D02*
Y126849D01*
G01X1343778Y155322D02*
Y294105D01*
G01X1354522Y144578D02*
X1343778Y155322D01*
G01X1354522Y134332D02*
Y144578D01*
G01X1351665Y131475D02*
X1354522Y134332D01*
G01X1351665Y128325D02*
Y131475D01*
G01X1349931Y134928D02*
X1348050Y133047D01*
G01X1349931Y138361D02*
Y134928D01*
G01X1379310Y134675D02*
X1350228Y163757D01*
G01D02*
Y292084D01*
G01X1395257Y131516D02*
X1361225Y165548D01*
G01X1329747Y127523D02*
X1329746Y127522D01*
G01X1329747Y130217D02*
Y127523D01*
G01X1334622Y125501D02*
X1334621Y125500D01*
G01X1334622Y132239D02*
Y125501D01*
G01X1334621Y132240D02*
X1334622Y132239D01*
G01X1334621Y132465D02*
Y132240D01*
G01X1330339Y136747D02*
X1334621Y132465D01*
G01X1330339Y141489D02*
Y136747D01*
G01X1395931Y133141D02*
X1362850Y166222D01*
G01X1357772Y132984D02*
X1356119Y131331D01*
G01X1357772Y146230D02*
Y132984D01*
G01X1347490Y156512D02*
X1357772Y146230D01*
G01X1347490Y293219D02*
Y156512D01*
G01X1382310Y135918D02*
X1353228Y165000D01*
G01X1352897Y135595D02*
X1349675Y132373D01*
G01X1352897Y143403D02*
Y135595D01*
G01X1342152Y154148D02*
X1352897Y143403D01*
G01X1342152Y294778D02*
Y154148D01*
G01X1333988Y161471D02*
Y190109D01*
G01X1330008Y147750D02*
Y175121D01*
G01X1335470Y142288D02*
X1330008Y147750D01*
G01X1335470Y133915D02*
Y142288D01*
G01X1336246Y133139D02*
X1335470Y133915D01*
G01X1336246Y132914D02*
Y133139D01*
G01X1336247Y132913D02*
X1336246Y132914D01*
G01X1336247Y124827D02*
Y132913D01*
G01X1336246Y124826D02*
X1336247Y124827D01*
G01X1358573Y165827D02*
Y290900D01*
G01X1372274Y189933D02*
Y272874D01*
G01X1398810Y163397D02*
X1372274Y189933D01*
G01X1370275Y169714D02*
Y297075D01*
G01X1355991Y165910D02*
Y275272D01*
G01X1361225Y165548D02*
Y425394D01*
G01X1362850Y166222D02*
Y426068D01*
G01X1353228Y165000D02*
Y290841D01*
G01X1330300Y193797D02*
Y296242D01*
G01X1333988Y190109D02*
X1330300Y193797D01*
G01X1351124Y299152D02*
X1345865Y293893D01*
G01X1351124Y420531D02*
Y299152D01*
G01X1331667Y300350D02*
Y419331D01*
G01X1375700Y302500D02*
Y413400D01*
G01X1370275Y297075D02*
X1375700Y302500D01*
G01X1349499Y299826D02*
Y419857D01*
G01X1343778Y294105D02*
X1349499Y299826D01*
G01X1355487Y297343D02*
Y423016D01*
G01X1350228Y292084D02*
X1355487Y297343D01*
G01X1352749Y298478D02*
X1347490Y293219D01*
G01X1352749Y421205D02*
Y298478D01*
G01X1358487Y296100D02*
Y424259D01*
G01X1353228Y290841D02*
X1358487Y296100D01*
G01X1347874Y300500D02*
X1342152Y294778D01*
G01X1347874Y419183D02*
Y300500D01*
G01X1338460Y304402D02*
Y415280D01*
G01X1330300Y296242D02*
X1338460Y304402D01*
G01X1336600Y645283D02*
Y667800D01*
G01X1330534Y629916D02*
Y624883D01*
G01X1343175Y642557D02*
X1330534Y629916D01*
G01X1343175Y665074D02*
Y642557D01*
G01X1341550Y665748D02*
Y643231D01*
G01X1344800Y641883D02*
Y662800D01*
G01X1336000Y633083D02*
X1344800Y641883D01*
G01X1336000Y627000D02*
Y633083D01*
G01X1342299Y688173D02*
X1370518Y716392D01*
G01X1342299Y673499D02*
Y688173D01*
G01X1336600Y667800D02*
X1342299Y673499D01*
G01X1348874Y670773D02*
X1343175Y665074D01*
G01X1348874Y685075D02*
Y670773D01*
G01X1379044Y715245D02*
X1348874Y685075D01*
G01X1331349Y679701D02*
Y698349D01*
G01X1347249Y671447D02*
X1341550Y665748D01*
G01X1347249Y685749D02*
Y671447D01*
G01X1376844Y715344D02*
X1347249Y685749D01*
G01X1351901Y685803D02*
X1380669Y714571D01*
G01X1351901Y669901D02*
Y685803D01*
G01X1344800Y662800D02*
X1351901Y669901D01*
G01X1340674Y689289D02*
X1368447Y717062D01*
G01X1340674Y676224D02*
Y689289D01*
G01X1333249Y679302D02*
Y697624D01*
G01X1338700Y771500D02*
Y719102D01*
G01X1370518Y716392D02*
Y789777D01*
G01X1336238Y718939D02*
Y772862D01*
G01X1344062Y718292D02*
Y737800D01*
G01X1349761Y716761D02*
Y777308D01*
G01X1331349Y698349D02*
X1349761Y716761D01*
G01X1376844Y791956D02*
Y715344D01*
G01X1368447Y717062D02*
Y790447D01*
G01X1351386Y715761D02*
Y776634D01*
G01X1333249Y697624D02*
X1351386Y715761D01*
G01X1340638Y774222D02*
Y718741D01*
G01X1347600Y717587D02*
Y734078D01*
G01X1334300Y771200D02*
Y719300D01*
G01X1370518Y789777D02*
X1377843Y797102D01*
G01X1334329Y774771D02*
Y775831D01*
G01X1336238Y772862D02*
X1334329Y774771D01*
G01X1349761Y777308D02*
X1371181Y798728D01*
G01X1382600Y797712D02*
X1376844Y791956D01*
G01X1368447Y790447D02*
X1375905Y797905D01*
G01X1351386Y776634D02*
X1372806Y798054D01*
G01X1338729Y776131D02*
X1340638Y774222D01*
G01X1377843Y797102D02*
Y971843D01*
G01X1341219Y813918D02*
Y933282D01*
G01X1371181Y798728D02*
Y1143681D01*
G01X1375905Y797905D02*
Y1136205D01*
G01X1372806Y798054D02*
Y1142806D01*
G01X1346080Y814800D02*
Y907004D01*
G01X1377843Y971843D02*
X1378100Y972100D01*
G01X1339404Y969600D02*
Y1025410D01*
G01X1353900Y970024D02*
Y1010769D01*
G01X1353762Y969886D02*
X1353900Y970024D01*
G01X1365551Y1028250D02*
Y1048445D01*
G01X1339404Y1025410D02*
X1364903Y1050909D01*
G01X1353900Y1010769D02*
X1349829Y1014840D01*
G01X1367103Y1049997D02*
Y1093288D01*
G01X1365551Y1048445D02*
X1367103Y1049997D01*
G01X1364903Y1050909D02*
Y1092376D01*
G01X1358064Y1102327D02*
Y1141693D01*
G01X1367103Y1093288D02*
X1358064Y1102327D01*
G01X1360264Y1115375D02*
Y1138988D01*
G01X1361074Y1114565D02*
X1360264Y1115375D01*
G01X1355733Y1101546D02*
Y1241900D01*
G01X1364903Y1092376D02*
X1355733Y1101546D01*
G01X1358064Y1141693D02*
X1360238Y1143867D01*
G01X1365551Y1171788D02*
Y1353500D01*
G01X1362511Y1168748D02*
X1365551Y1171788D01*
G01X1362511Y1141235D02*
Y1168748D01*
G01X1360264Y1138988D02*
X1362511Y1141235D01*
G01X1371181Y1143681D02*
X1378625Y1151125D01*
G01X1375905Y1136205D02*
X1381875Y1142175D01*
G01X1372806Y1142806D02*
X1380250Y1150250D01*
G01X1378625Y1321075D02*
X1369600Y1330100D01*
G01X1380250Y1323450D02*
X1373700Y1330000D01*
G01X1416892Y108699D02*
Y130255D01*
G01X1419488Y106103D02*
X1416892Y108699D01*
G01X1415017Y99817D02*
Y124972D01*
G01X1412402Y97202D02*
X1415017Y99817D01*
G01X1412402Y96654D02*
Y97202D01*
G01X1398228Y110827D02*
X1391700Y117355D01*
G01X1398228Y97372D02*
X1379310Y116290D01*
G01X1398228Y96654D02*
Y97372D01*
G01X1405315Y114764D02*
X1401600Y118479D01*
G01X1422199Y101030D02*
Y153583D01*
G01X1426575Y96654D02*
X1422199Y101030D01*
G01X1424074Y104667D02*
Y155054D01*
G01X1426575Y102166D02*
X1424074Y104667D01*
G01X1398228Y102166D02*
X1382310Y118084D01*
G01X1393816Y120751D02*
Y130584D01*
G01X1398228Y116339D02*
X1393816Y120751D01*
G01X1398810Y148337D02*
Y163397D01*
G01X1416892Y130255D02*
X1398810Y148337D01*
G01X1391700Y117355D02*
Y130201D01*
G01X1379310Y116290D02*
Y134675D01*
G01X1395276Y131516D02*
X1395257D01*
G01X1401600Y125192D02*
X1395276Y131516D01*
G01X1401600Y118479D02*
Y125192D01*
G01X1422199Y153583D02*
X1380100Y195682D01*
G01X1424074Y155054D02*
X1388000Y191128D01*
G01X1396345Y133141D02*
X1395931D01*
G01X1404362Y125124D02*
X1396345Y133141D01*
G01X1404476Y125124D02*
X1404362D01*
G01X1405315Y124285D02*
X1404476Y125124D01*
G01X1405315Y120276D02*
Y124285D01*
G01X1382310Y118084D02*
Y135918D01*
G01X1423661Y171034D02*
Y274600D01*
G01X1427663Y167032D02*
X1423661Y171034D01*
G01X1380100Y195682D02*
Y419321D01*
G01X1388000Y191128D02*
Y431200D01*
G01X1423661Y274600D02*
X1431909Y282848D01*
G01X1384713Y323200D02*
Y417449D01*
G01X1388000Y431200D02*
X1395300Y438500D01*
G01X1379044Y791044D02*
Y715245D01*
G01X1381244Y715244D02*
Y790132D01*
G01X1380669Y714669D02*
X1381244Y715244D01*
G01X1380669Y714571D02*
Y714669D01*
G01X1383952Y717435D02*
Y788952D01*
G01X1384801Y796801D02*
X1379044Y791044D01*
G01X1381244Y790132D02*
X1387500Y796388D01*
G01X1383952Y788952D02*
X1395843Y800843D01*
G01X1384801Y798623D02*
Y796801D01*
G01X1384800Y798624D02*
X1384801Y798623D01*
G01X1384800Y1002666D02*
Y798624D01*
G01X1382600Y1063600D02*
Y797712D01*
G01X1387500Y796388D02*
Y881841D01*
G01X1395843Y800843D02*
Y927557D01*
G01X1387500Y881841D02*
X1392355Y886696D01*
G01X1380300Y930200D02*
Y1117600D01*
G01X1395843Y927557D02*
X1391000Y932400D01*
G01X1388500Y1069500D02*
X1382600Y1063600D01*
G01X1388500Y1224900D02*
Y1069500D01*
G01X1383900Y1121200D02*
Y1166689D01*
G01X1380300Y1117600D02*
X1383900Y1121200D01*
G01Y1166689D02*
X1383899Y1166690D01*
G01X1378625Y1151125D02*
Y1321075D01*
G01X1381875Y1142175D02*
Y1329525D01*
G01X1380250Y1150250D02*
Y1323450D01*
G01X1381875Y1329525D02*
X1381800Y1329600D01*
G01X1456373Y168971D02*
Y450446D01*
G01X1431909Y282848D02*
Y359311D01*
G01D02*
Y469425D01*
G01X1456373Y450446D02*
X1521216Y515289D01*
G01X1431909Y469425D02*
X1474700Y512216D01*
G01X1469170Y497970D02*
X1494782D01*
G01X1463000Y491800D02*
X1469170Y497970D01*
G01X1463000Y490638D02*
Y491800D01*
G01X1455200Y618559D02*
Y831000D01*
G01X1455202Y618557D02*
X1455200Y618559D01*
G01X1468870Y611500D02*
Y828530D01*
G01X1521216Y559154D02*
X1468870Y611500D01*
G01X1464470Y609676D02*
Y826330D01*
G01X1515938Y558208D02*
X1464470Y609676D01*
G01X1466670Y610588D02*
Y826955D01*
G01X1519016Y558242D02*
X1466670Y610588D01*
G01X1455200Y831000D02*
X1440100Y846100D01*
G01X1468870Y828530D02*
X1447600Y849800D01*
G01X1464470Y826330D02*
X1442500Y848300D01*
G01X1466670Y826955D02*
X1444900Y848725D01*
G01X1440100Y846100D02*
Y893100D01*
G01X1447600Y849800D02*
Y909600D01*
G01X1442500Y848300D02*
Y941000D01*
G01X1435300Y882700D02*
Y938000D01*
G01X1444900Y848725D02*
Y939500D01*
G01X1440100Y893100D02*
X1440500Y893500D01*
G01X1447600Y909600D02*
X1448000Y910000D01*
G01X1463616Y1051371D02*
Y969265D01*
G01X1448400Y946900D02*
Y1046900D01*
G01X1442500Y941000D02*
X1448400Y946900D01*
G01X1446213Y948913D02*
Y1062300D01*
G01X1435300Y938000D02*
X1446213Y948913D01*
G01X1451800Y946400D02*
Y1004700D01*
G01X1444900Y939500D02*
X1451800Y946400D01*
G01X1473600Y1061355D02*
X1463616Y1051371D01*
G01X1473600Y1242777D02*
Y1061355D01*
G01X1467000Y1065500D02*
Y1221800D01*
G01X1448400Y1046900D02*
X1467000Y1065500D01*
G01X1521225Y108627D02*
Y130561D01*
G01X1518701Y106103D02*
X1521225Y108627D01*
G01X1518701Y100591D02*
X1523100Y104990D01*
G01X1494637Y157149D02*
Y453453D01*
G01X1521225Y130561D02*
X1494637Y157149D01*
G01X1496262Y158238D02*
Y452779D01*
G01X1523100Y131400D02*
X1496262Y158238D01*
G01X1508925Y454567D02*
Y323200D01*
G01X1494637Y453453D02*
X1546735Y505551D01*
G01X1496262Y452779D02*
X1548360Y504877D01*
G01X1556048Y501690D02*
X1508925Y454567D01*
G01X1494782Y497970D02*
X1515938Y519126D01*
G01X1492741Y489926D02*
X1519016Y516201D01*
G01X1481938Y489926D02*
X1492741D01*
G01X1474700Y512216D02*
Y569100D01*
G01X1521216Y515289D02*
Y559154D01*
G01X1515938Y519126D02*
Y558208D01*
G01X1519016Y516201D02*
Y558242D01*
G01X1546735Y568417D02*
X1498287Y616865D01*
G01X1548360Y569091D02*
X1499912Y617539D01*
G01X1511300Y617026D02*
X1556048Y572278D01*
G01X1511300Y706000D02*
Y617026D01*
G01X1498287Y616865D02*
Y705839D01*
G01X1499912Y617539D02*
Y706513D01*
G01X1503469Y713831D02*
X1511300Y706000D01*
G01X1503469Y968104D02*
Y713831D01*
G01X1494125Y710001D02*
Y929725D01*
G01X1498287Y705839D02*
X1494125Y710001D01*
G01X1495750Y710675D02*
Y929051D01*
G01X1499912Y706513D02*
X1495750Y710675D01*
G01X1505900Y717600D02*
Y930400D01*
G01X1497400Y933000D02*
Y1120700D01*
G01X1494125Y929725D02*
X1497400Y933000D01*
G01X1507400Y941800D02*
X1521200Y928000D01*
G01X1499500Y932801D02*
Y1099500D01*
G01X1495750Y929051D02*
X1499500Y932801D01*
G01X1503394Y968179D02*
X1503469Y968104D01*
G01X1507400Y971600D02*
Y941800D01*
G01X1502500Y976500D02*
X1507400Y971600D01*
G01X1502500Y1098500D02*
Y976500D01*
G01X1478200Y970270D02*
Y1017160D01*
G01X1477974Y970044D02*
X1478200Y970270D01*
G01X1481529Y1030500D02*
Y1136065D01*
G01X1478200Y1017160D02*
X1478194Y1017166D01*
G01X1502200Y1125500D02*
Y1150000D01*
G01X1497400Y1120700D02*
X1502200Y1125500D01*
G01X1507400Y1103400D02*
X1502500Y1098500D01*
G01X1507400Y1168100D02*
Y1103400D01*
G01X1504400Y1104400D02*
Y1164600D01*
G01X1499500Y1099500D02*
X1504400Y1104400D01*
G01X1485608Y1113628D02*
Y1133484D01*
G01X1497400Y1154800D02*
Y1342300D01*
G01X1502200Y1150000D02*
X1497400Y1154800D01*
G01X1481529Y1136065D02*
X1485833Y1140369D01*
G01X1504200Y1171300D02*
X1507400Y1168100D01*
G01X1502000Y1167000D02*
Y1341200D01*
G01X1504400Y1164600D02*
X1502000Y1167000D01*
G01X1491662Y1139538D02*
Y1351300D01*
G01X1485608Y1133484D02*
X1491662Y1139538D01*
G01X1497400Y1342300D02*
X1497200Y1342500D01*
G01X1501600Y1341600D02*
Y1342300D01*
G01X1502000Y1341200D02*
X1501600Y1341600D01*
G01X1523100Y104990D02*
Y131400D01*
G01X1568500Y438500D02*
Y544100D01*
G01X1556048Y572278D02*
Y501690D01*
G01X1546735Y505551D02*
Y568417D01*
G01X1548360Y504877D02*
Y569091D01*
G01X1570425Y888475D02*
X1570500Y888400D01*
G01X1570425Y1062000D02*
Y888475D01*
G01X1566550Y1108550D02*
X1577435Y1097665D01*
G01X1566550Y1183100D02*
Y1108550D01*
G01X1558650Y1191000D02*
X1566550Y1183100D01*
G01X1558650Y1217426D02*
Y1191000D01*
G01X1590600Y177248D02*
Y389788D01*
G01X1579371Y166019D02*
X1590600Y177248D01*
G01X1592800Y294876D02*
Y390700D01*
G01X1622738Y264938D02*
X1592800Y294876D01*
G01X1577580Y402808D02*
Y608149D01*
G01X1590600Y389788D02*
X1577580Y402808D01*
G01X1702838Y316862D02*
X1601406Y418294D01*
G01X1580249Y403251D02*
Y608519D01*
G01X1592800Y390700D02*
X1580249Y403251D01*
G01X1601406Y418294D02*
Y515623D01*
G01X1586596Y582824D02*
Y518723D01*
G01X1602370Y518677D02*
Y593214D01*
G01X1602683Y518364D02*
X1602370Y518677D01*
G01X1602683Y516758D02*
Y518364D01*
G01X1601548Y515623D02*
X1602683Y516758D01*
G01X1601406Y515623D02*
X1601548D01*
G01X1600745Y517561D02*
Y594674D01*
G01X1622465Y618693D02*
X1586596Y582824D01*
G01X1602370Y593214D02*
X1625715Y616559D01*
G01X1600745Y594674D02*
X1624090Y618019D01*
G01X1580864Y611433D02*
Y674804D01*
G01X1577580Y608149D02*
X1580864Y611433D01*
G01X1578926Y618657D02*
Y675246D01*
G01X1582489Y610759D02*
Y674130D01*
G01X1580249Y608519D02*
X1582489Y610759D01*
G01X1587400Y681340D02*
Y912200D01*
G01X1580864Y674804D02*
X1587400Y681340D01*
G01X1597938Y680191D02*
X1622465Y655664D01*
G01X1597938Y924762D02*
Y680191D01*
G01X1602370Y681736D02*
Y908570D01*
G01X1625715Y658391D02*
X1602370Y681736D01*
G01X1608266Y685134D02*
X1629212Y664188D01*
G01X1608266Y906866D02*
Y685134D01*
G01X1611175Y685812D02*
X1638890Y658097D01*
G01X1611175Y906496D02*
Y685812D01*
G01X1604985Y681420D02*
X1627340Y659065D01*
G01X1604985Y907727D02*
Y681420D01*
G01X1613600Y687600D02*
Y899600D01*
G01X1640515Y660685D02*
X1613600Y687600D01*
G01X1585125Y681445D02*
Y895475D01*
G01X1578926Y675246D02*
X1585125Y681445D01*
G01X1600745Y682410D02*
Y925067D01*
G01X1600744Y682409D02*
X1600745Y682410D01*
G01X1600744Y681063D02*
Y682409D01*
G01X1624090Y657717D02*
X1600744Y681063D01*
G01X1592800Y684441D02*
Y922200D01*
G01X1582489Y674130D02*
X1592800Y684441D01*
G01X1616164Y724212D02*
Y897291D01*
G01X1621138Y719238D02*
X1616164Y724212D01*
G01X1577435Y945265D02*
X1597938Y924762D01*
G01X1602370Y908570D02*
X1608200Y914400D01*
G01X1618200Y916800D02*
X1608266Y906866D01*
G01X1621787Y917108D02*
X1611175Y906496D01*
G01X1611939Y914681D02*
X1604985Y907727D01*
G01X1611939Y959746D02*
Y914681D01*
G01X1613600Y899600D02*
X1630938Y916938D01*
G01X1616164Y897291D02*
X1633600Y914727D01*
G01X1585125Y895475D02*
X1584800Y895800D01*
G01X1600745Y925067D02*
X1580381Y945431D01*
G01X1592800Y922200D02*
X1574576Y940424D01*
G01X1577435Y1097665D02*
Y945265D01*
G01X1602407Y970190D02*
Y1019359D01*
G01X1602187Y969970D02*
X1602407Y970190D01*
G01X1587829Y969191D02*
Y1074229D01*
G01X1612745Y960552D02*
X1611939Y959746D01*
G01X1612745Y962158D02*
Y960552D01*
G01X1611939Y962964D02*
X1612745Y962158D01*
G01X1611939Y969624D02*
Y962964D01*
G01X1615494Y973179D02*
X1611939Y969624D01*
G01X1580381Y945431D02*
Y1007066D01*
G01X1574576Y940424D02*
Y976700D01*
G01X1602407Y1019359D02*
X1602400Y1019366D01*
G01X1587829Y1074229D02*
X1613400Y1099800D01*
G01D02*
Y1236500D01*
G01X1636957Y401643D02*
X1827796Y210804D01*
G01X1636957Y449845D02*
Y401643D01*
G01X1640230Y429170D02*
X1837200Y232200D01*
G01X1638807Y395393D02*
X1747550Y286650D01*
G01X1638807Y397494D02*
Y395393D01*
G01X1635332Y400969D02*
X1638807Y397494D01*
G01X1635332Y449171D02*
Y400969D01*
G01X1622176Y464626D02*
X1636957Y449845D01*
G01X1640230Y448871D02*
Y429170D01*
G01X1623801Y465300D02*
X1640230Y448871D01*
G01X1620551Y463952D02*
X1635332Y449171D01*
G01X1788500Y302900D02*
X1625426Y465974D01*
G01X1622176Y597008D02*
Y464626D01*
G01X1623801Y596334D02*
Y465300D01*
G01X1620551Y609096D02*
Y463952D01*
G01X1625426Y465974D02*
Y595660D01*
G01X1629212Y604044D02*
X1622176Y597008D01*
G01X1638890Y611423D02*
X1623801Y596334D01*
G01X1625426Y595660D02*
X1640515Y610749D01*
G01X1622465Y655664D02*
Y618693D01*
G01X1625715Y616559D02*
Y658391D01*
G01X1629212Y664188D02*
Y604044D01*
G01X1638890Y658097D02*
Y611423D01*
G01X1627340Y615885D02*
X1620551Y609096D01*
G01X1627340Y659065D02*
Y615885D01*
G01X1640515Y610749D02*
Y660685D01*
G01X1624090Y618019D02*
Y657717D01*
G01X1643344Y887455D02*
X1663300Y907411D01*
G01X1646013Y884255D02*
X1665969Y904211D01*
G01X1659600Y909711D02*
Y1032885D01*
G01X1639644Y889755D02*
X1659600Y909711D01*
G01X1663300Y907411D02*
Y1032200D01*
G01X1630938Y916938D02*
Y973335D01*
G01X1633600Y914727D02*
Y936300D01*
G01X1665969Y904211D02*
Y1029838D01*
G01X1636400Y925800D02*
Y1087400D01*
G01X1630938Y973335D02*
X1629094Y975179D01*
G01X1659600Y1032885D02*
X1690315Y1063600D01*
G01X1663300Y1032200D02*
X1685100Y1054000D01*
G01X1620059Y1128071D02*
Y1032932D01*
G01X1665969Y1029838D02*
X1679300Y1043169D01*
G01X1633138Y1090662D02*
Y1165673D01*
G01X1636400Y1087400D02*
X1633138Y1090662D01*
G01X1624198Y1348798D02*
Y1111309D01*
G01X1624500Y1349100D02*
X1624198Y1348798D01*
G01X1702838Y183348D02*
Y316862D01*
G01X1703584Y182602D02*
X1702838Y183348D01*
G01X1703584Y166019D02*
Y182602D01*
G01X1709338Y520193D02*
Y686576D01*
G01X1711061Y518470D02*
X1709338Y520193D01*
G01X1711538Y532862D02*
Y686096D01*
G01X1725100Y519300D02*
X1711538Y532862D01*
G01X1705000Y648500D02*
Y618667D01*
G01X1704010Y649490D02*
X1705000Y648500D01*
G01X1704010Y672897D02*
Y649490D01*
G01X1707138Y676025D02*
X1704010Y672897D01*
G01X1707138Y686799D02*
Y676025D01*
G01X1716770Y696431D02*
X1707138Y686799D01*
G01X1709338Y686576D02*
X1718395Y695633D01*
G01X1711538Y686096D02*
X1720020Y694578D01*
G01X1704010Y898000D02*
X1732911Y869099D01*
G01X1703928Y934100D02*
X1687800Y950228D01*
G01X1786305Y934100D02*
X1703928D01*
G01X1704840Y936300D02*
X1787217D01*
G01X1690279Y950861D02*
X1704840Y936300D01*
G01X1734575Y872013D02*
X1668449Y938139D01*
G01X1736515Y873185D02*
X1671422Y938278D01*
G01X1692100Y923600D02*
Y939755D01*
G01X1687800Y950228D02*
Y1021141D01*
G01X1674814Y1028514D02*
Y961977D01*
G01X1690279Y1011526D02*
Y950861D01*
G01X1677055Y954637D02*
X1677056Y954636D01*
G01X1677055Y1026955D02*
Y954637D01*
G01X1680087Y952477D02*
Y1023983D01*
G01X1680012Y952402D02*
X1680087Y952477D01*
G01X1668449Y938139D02*
Y1027249D01*
G01X1671422Y938278D02*
Y1009266D01*
G01X1682476Y949379D02*
Y1018929D01*
G01X1692100Y939755D02*
X1682476Y949379D01*
G01X1687800Y1021141D02*
X1732579Y1065920D01*
G01X1710600Y1064300D02*
X1674814Y1028514D01*
G01X1715049Y1064949D02*
X1677055Y1026955D01*
G01X1668449Y1027249D02*
X1702838Y1061638D01*
G01X1682476Y1018929D02*
X1730379Y1066832D01*
G01X1690315Y1063600D02*
X1694638D01*
G01X1726512Y1069904D02*
X1691771Y1035163D01*
G01X1710600Y1231412D02*
Y1064300D01*
G01X1715049Y1234000D02*
Y1064949D01*
G01X1702838Y1061638D02*
Y1215300D01*
G01X1710617Y1231429D02*
X1710600Y1231412D01*
G01X1747550Y286650D02*
Y265000D01*
G01X1718395Y695633D02*
Y784132D01*
G01X1720020Y694578D02*
Y783458D01*
G01X1716770Y784806D02*
Y696431D01*
G01X1732911Y800947D02*
X1716770Y784806D01*
G01X1718395Y784132D02*
X1734575Y800312D01*
G01X1720020Y783458D02*
X1736515Y799953D01*
G01X1732911Y869099D02*
Y800947D01*
G01X1734575Y800312D02*
Y872013D01*
G01X1736515Y799953D02*
Y873185D01*
G01X1732579Y1065920D02*
Y1105179D01*
G01X1726512Y1135441D02*
Y1069904D01*
G01X1730379Y1066832D02*
Y1106091D01*
G01X1755900Y1128500D02*
Y1212704D01*
G01X1732579Y1105179D02*
X1755900Y1128500D01*
G01X1733245Y1125040D02*
Y1115503D01*
G01X1740026Y1131821D02*
X1733245Y1125040D01*
G01X1751400Y1127112D02*
Y1173900D01*
G01X1730379Y1106091D02*
X1751400Y1127112D01*
G01X1732768Y1141697D02*
X1726512Y1135441D01*
G01X1740026Y1346874D02*
Y1131821D01*
G01X1740000Y1346900D02*
X1740026Y1346874D01*
G01X1788500Y292000D02*
Y302900D01*
G01X1861000Y219500D02*
X1788500Y292000D01*
G01X1832678Y887727D02*
X1786305Y934100D01*
G01X1787217Y936300D02*
X1834304Y889213D01*
G01X1837200Y156789D02*
X1841021Y152968D01*
G01X1837200Y232200D02*
Y156789D01*
G01X1827796Y210804D02*
Y166019D01*
G01X1861000Y187634D02*
Y219500D01*
G01X1869500Y179134D02*
X1861000Y187634D01*
G01X1853917Y537618D02*
Y698255D01*
G01X1834896Y518597D02*
X1853917Y537618D01*
G01X1861317Y529707D02*
X1849045Y517435D01*
G01X1861317Y625083D02*
Y529707D01*
G01X1840855Y611393D02*
Y606200D01*
G01X1839667Y612581D02*
X1840855Y611393D01*
G01X1839667Y708438D02*
Y612581D01*
G01X1859786Y626614D02*
X1861317Y625083D01*
G01X1859786Y696670D02*
Y626614D01*
G01X1828700Y619736D02*
X1827667Y618703D01*
G01X1828700Y881819D02*
Y619736D01*
G01X1830757Y717348D02*
X1839667Y708438D01*
G01X1830757Y884063D02*
Y717348D01*
G01X1832678Y719494D02*
Y887727D01*
G01X1853917Y698255D02*
X1832678Y719494D01*
G01X1834304Y722152D02*
X1859786Y696670D01*
G01X1834304Y889213D02*
Y722152D01*
G01X1836078Y722891D02*
X1867400Y691569D01*
G01X1836078Y889996D02*
Y722891D01*
G01X1823937Y890883D02*
X1830757Y884063D01*
G01X1824170Y886349D02*
X1828700Y881819D01*
G01X1837865Y921500D02*
X1877900Y961535D01*
G01X1819541Y921500D02*
X1837865D01*
G01X1813851Y912223D02*
X1836078Y889996D01*
G01X1813851Y927406D02*
Y912223D01*
G01X1868500Y1110000D02*
X1840585Y1137915D01*
G01X1836200Y1130000D02*
X1833724Y1132476D01*
G01X1840585Y1137915D02*
Y1151653D01*
G01X1842000Y1164686D02*
Y1344700D01*
G01X1833724Y1156410D02*
X1842000Y1164686D01*
G01X1833724Y1132476D02*
Y1156410D01*
G01X1867400Y635600D02*
X1869500Y633500D01*
G01X1867400Y691569D02*
Y635600D01*
G01X1877900Y961535D02*
Y1028700D01*
G01D02*
X1887402Y1038202D01*
G01X1868500Y1079127D02*
Y1110000D01*
G01X1864617Y1075244D02*
X1868500Y1079127D01*
G01X1864617Y1040934D02*
Y1075244D01*
G01X1887402Y1038202D02*
Y1050193D01*
M02*
